FILE_TYPE = MACRO_DRAWING;
SET COLOR_WIRE YELLOW;
SET COLOR_PROP ORANGE;
SET COLOR_DOT WHITE;
SET COLOR_ARC YELLOW;
SET COLOR_BODY GREEN;
SET COLOR_NOTE PURPLE;
SET PROP_DISPLAY VALUE;
SET PAGE_NUMBER P79;
FORCEADD OFFPAGE..1
R 2
(-1975 5050);
FORCEPROP 2 LAST $XR1 158 
J 0
(-1699 5050);
DISPLAY 0.638298 (-1699 5050);
PAINT MONO (-1699 5050);
FORCEPROP 2 LAST $XR0 82 
J 0
(-1789 5050);
DISPLAY 0.638298 (-1789 5050);
PAINT MONO (-1789 5050);
FORCEPROP 2 LAST PATH I1226
J 0
(-1675 5100);
DISPLAY 0.680851 (-1675 5100);
DISPLAY INVISIBLE (-1675 5100);
FORCEPROP 2 LAST CDS_LIB standard
J 0
(-1975 5050);
DISPLAY INVISIBLE (-1975 5050);
FORCEPROP 1 LAST OFFPAGE TRUE
J 2
(-2300 4925);
DISPLAY 0.872340 (-2300 4925);
PAINT GREEN (-2300 4925);
DISPLAY INVISIBLE (-2300 4925);
FORCEPROP 1 LAST COMMENT_BODY TRUE
J 2
(-2100 4950);
DISPLAY 0.872340 (-2100 4950);
PAINT GREEN (-2100 4950);
DISPLAY INVISIBLE (-2100 4950);
FORCEADD OFFPAGE..1
R 2
(-1975 5000);
FORCEPROP 2 LAST $XR1 117 
J 0
(-1699 5000);
DISPLAY 0.638298 (-1699 5000);
PAINT MONO (-1699 5000);
FORCEPROP 2 LAST $XR0 82 
J 0
(-1789 5000);
DISPLAY 0.638298 (-1789 5000);
PAINT MONO (-1789 5000);
FORCEPROP 2 LAST PATH I1227
J 0
(-1675 5050);
DISPLAY 0.680851 (-1675 5050);
DISPLAY INVISIBLE (-1675 5050);
FORCEPROP 2 LAST CDS_LIB standard
J 0
(-1975 5000);
DISPLAY INVISIBLE (-1975 5000);
FORCEPROP 1 LAST OFFPAGE TRUE
J 2
(-2305 4870);
PAINT GREEN (-2305 4870);
DISPLAY INVISIBLE (-2305 4870);
FORCEPROP 1 LAST COMMENT_BODY TRUE
J 2
(-2105 4900);
DISPLAY 1.106383 (-2105 4900);
PAINT PEACH (-2105 4900);
DISPLAY INVISIBLE (-2105 4900);
FORCEADD OFFPAGE..1
R 2
(-1975 4950);
FORCEPROP 2 LAST $XR1 118 
J 0
(-1669 4950);
DISPLAY 0.638298 (-1669 4950);
PAINT MONO (-1669 4950);
FORCEPROP 2 LAST $XR0 117 
J 0
(-1789 4950);
DISPLAY 0.638298 (-1789 4950);
PAINT MONO (-1789 4950);
FORCEPROP 2 LAST PATH I1228
J 0
(-1650 5000);
DISPLAY 0.680851 (-1650 5000);
DISPLAY INVISIBLE (-1650 5000);
FORCEPROP 2 LAST CDS_LIB standard
J 0
(-1975 4950);
DISPLAY INVISIBLE (-1975 4950);
FORCEPROP 1 LAST OFFPAGE TRUE
J 2
(-2300 4825);
DISPLAY 0.872340 (-2300 4825);
PAINT GREEN (-2300 4825);
DISPLAY INVISIBLE (-2300 4825);
FORCEPROP 1 LAST COMMENT_BODY TRUE
J 2
(-2100 4850);
DISPLAY 0.872340 (-2100 4850);
PAINT GREEN (-2100 4850);
DISPLAY INVISIBLE (-2100 4850);
FORCEADD OFFPAGE..3
(-1975 4900);
FORCEPROP 2 LAST $XR1 118 
J 0
(-1641 4900);
DISPLAY 0.638298 (-1641 4900);
PAINT MONO (-1641 4900);
FORCEPROP 2 LAST $XR0 117 
J 0
(-1761 4900);
DISPLAY 0.638298 (-1761 4900);
PAINT MONO (-1761 4900);
FORCEPROP 2 LAST PATH I1229
J 0
(-1625 4950);
DISPLAY 0.680851 (-1625 4950);
DISPLAY INVISIBLE (-1625 4950);
FORCEPROP 2 LAST CDS_LIB standard
J 0
(-1975 4900);
DISPLAY INVISIBLE (-1975 4900);
FORCEPROP 1 LAST OFFPAGE TRUE
J 0
(-1650 4775);
DISPLAY 0.872340 (-1650 4775);
PAINT GREEN (-1650 4775);
DISPLAY INVISIBLE (-1650 4775);
FORCEPROP 1 LAST COMMENT_BODY TRUE
J 0
(-2025 4800);
DISPLAY 0.872340 (-2025 4800);
PAINT GREEN (-2025 4800);
DISPLAY INVISIBLE (-2025 4800);
FORCEADD OFFPAGE..2
(-1975 4850);
FORCEPROP 2 LAST $XR0 126 
J 0
(-1786 4850);
DISPLAY 0.638298 (-1786 4850);
PAINT MONO (-1786 4850);
FORCEPROP 2 LAST PATH I1230
J 0
(-1775 4900);
DISPLAY 0.680851 (-1775 4900);
DISPLAY INVISIBLE (-1775 4900);
FORCEPROP 2 LAST CDS_LIB standard
J 0
(-1975 4850);
DISPLAY INVISIBLE (-1975 4850);
FORCEPROP 1 LAST OFFPAGE TRUE
J 0
(-1650 4725);
DISPLAY 0.872340 (-1650 4725);
PAINT GREEN (-1650 4725);
DISPLAY INVISIBLE (-1650 4725);
FORCEPROP 1 LAST COMMENT_BODY TRUE
J 0
(-2020 4755);
DISPLAY 0.872340 (-2020 4755);
PAINT GREEN (-2020 4755);
DISPLAY INVISIBLE (-2020 4755);
FORCEADD OFFPAGE..2
(-1975 4800);
FORCEPROP 2 LAST $XR0 127 
J 0
(-1786 4800);
DISPLAY 0.638298 (-1786 4800);
PAINT MONO (-1786 4800);
FORCEPROP 2 LAST PATH I1231
J 0
(-1775 4850);
DISPLAY 0.680851 (-1775 4850);
DISPLAY INVISIBLE (-1775 4850);
FORCEPROP 2 LAST CDS_LIB standard
J 0
(-1975 4800);
DISPLAY INVISIBLE (-1975 4800);
FORCEPROP 1 LAST OFFPAGE TRUE
J 0
(-1650 4675);
DISPLAY 0.872340 (-1650 4675);
PAINT GREEN (-1650 4675);
DISPLAY INVISIBLE (-1650 4675);
FORCEPROP 1 LAST COMMENT_BODY TRUE
J 0
(-2020 4705);
DISPLAY 0.872340 (-2020 4705);
PAINT GREEN (-2020 4705);
DISPLAY INVISIBLE (-2020 4705);
FORCEADD OFFPAGE..3
(-1975 4700);
FORCEPROP 2 LAST $XR1 118 
J 0
(-1641 4700);
DISPLAY 0.638298 (-1641 4700);
PAINT MONO (-1641 4700);
FORCEPROP 2 LAST $XR0 117 
J 0
(-1761 4700);
DISPLAY 0.638298 (-1761 4700);
PAINT MONO (-1761 4700);
FORCEPROP 2 LAST PATH I1232
J 0
(-1625 4750);
DISPLAY 0.680851 (-1625 4750);
DISPLAY INVISIBLE (-1625 4750);
FORCEPROP 2 LAST CDS_LIB standard
J 0
(-1975 4700);
DISPLAY INVISIBLE (-1975 4700);
FORCEPROP 1 LAST OFFPAGE TRUE
J 0
(-1650 4575);
DISPLAY 0.872340 (-1650 4575);
PAINT GREEN (-1650 4575);
DISPLAY INVISIBLE (-1650 4575);
FORCEPROP 1 LAST COMMENT_BODY TRUE
J 0
(-2025 4600);
DISPLAY 0.872340 (-2025 4600);
PAINT GREEN (-2025 4600);
DISPLAY INVISIBLE (-2025 4600);
FORCEADD OFFPAGE..2
(-1975 4750);
FORCEPROP 2 LAST $XR0 110 
J 0
(-1786 4750);
DISPLAY 0.638298 (-1786 4750);
PAINT MONO (-1786 4750);
FORCEPROP 2 LAST PATH I1233
J 0
(-1775 4800);
DISPLAY 0.680851 (-1775 4800);
DISPLAY INVISIBLE (-1775 4800);
FORCEPROP 1 LAST COMMENT_BODY TRUE
J 0
(-2020 4655);
DISPLAY 0.872340 (-2020 4655);
PAINT GREEN (-2020 4655);
DISPLAY INVISIBLE (-2020 4655);
FORCEPROP 1 LAST OFFPAGE TRUE
J 0
(-1650 4625);
DISPLAY 0.872340 (-1650 4625);
PAINT GREEN (-1650 4625);
DISPLAY INVISIBLE (-1650 4625);
FORCEPROP 2 LAST CDS_LIB standard
J 0
(-1975 4750);
DISPLAY INVISIBLE (-1975 4750);
FORCEADD OFFPAGE..3
(-1975 4600);
FORCEPROP 2 LAST $XR2 134 
J 0
(-1521 4600);
DISPLAY 0.638298 (-1521 4600);
PAINT MONO (-1521 4600);
FORCEPROP 2 LAST $XR1 118 
J 0
(-1641 4600);
DISPLAY 0.638298 (-1641 4600);
PAINT MONO (-1641 4600);
FORCEPROP 2 LAST $XR0 117 
J 0
(-1761 4600);
DISPLAY 0.638298 (-1761 4600);
PAINT MONO (-1761 4600);
FORCEPROP 2 LAST PATH I1234
J 0
(-1500 4650);
DISPLAY 0.680851 (-1500 4650);
DISPLAY INVISIBLE (-1500 4650);
FORCEPROP 2 LAST CDS_LIB standard
J 0
(-1975 4600);
DISPLAY INVISIBLE (-1975 4600);
FORCEPROP 1 LAST OFFPAGE TRUE
J 0
(-1650 4475);
DISPLAY 0.872340 (-1650 4475);
PAINT GREEN (-1650 4475);
DISPLAY INVISIBLE (-1650 4475);
FORCEPROP 1 LAST COMMENT_BODY TRUE
J 0
(-2025 4500);
DISPLAY 0.872340 (-2025 4500);
PAINT GREEN (-2025 4500);
DISPLAY INVISIBLE (-2025 4500);
FORCEADD OFFPAGE..1
R 2
(-1975 4650);
FORCEPROP 2 LAST $XR2 134 
J 0
(-1519 4650);
DISPLAY 0.638298 (-1519 4650);
PAINT MONO (-1519 4650);
FORCEPROP 2 LAST $XR1 118 
J 0
(-1639 4650);
DISPLAY 0.638298 (-1639 4650);
PAINT MONO (-1639 4650);
FORCEPROP 2 LAST $XR0 117 
J 0
(-1759 4650);
DISPLAY 0.638298 (-1759 4650);
PAINT MONO (-1759 4650);
FORCEPROP 2 LAST PATH I1235
J 0
(-1525 4700);
DISPLAY 0.680851 (-1525 4700);
DISPLAY INVISIBLE (-1525 4700);
FORCEPROP 2 LAST CDS_LIB standard
J 0
(-1975 4650);
DISPLAY INVISIBLE (-1975 4650);
FORCEPROP 1 LAST OFFPAGE TRUE
J 2
(-2300 4525);
DISPLAY 0.872340 (-2300 4525);
PAINT GREEN (-2300 4525);
DISPLAY INVISIBLE (-2300 4525);
FORCEPROP 1 LAST COMMENT_BODY TRUE
J 2
(-2100 4550);
DISPLAY 0.872340 (-2100 4550);
PAINT GREEN (-2100 4550);
DISPLAY INVISIBLE (-2100 4550);
FORCEADD OFFPAGE..1
R 2
(-1975 4550);
FORCEPROP 2 LAST $XR0 117 
J 0
(-1759 4550);
DISPLAY 0.638298 (-1759 4550);
PAINT MONO (-1759 4550);
FORCEPROP 2 LAST PATH I1236
J 0
(-1775 4600);
DISPLAY 0.680851 (-1775 4600);
DISPLAY INVISIBLE (-1775 4600);
FORCEPROP 1 LAST COMMENT_BODY TRUE
J 2
(-2105 4450);
DISPLAY 1.106383 (-2105 4450);
PAINT PEACH (-2105 4450);
DISPLAY INVISIBLE (-2105 4450);
FORCEPROP 1 LAST OFFPAGE TRUE
J 2
(-2305 4420);
PAINT GREEN (-2305 4420);
DISPLAY INVISIBLE (-2305 4420);
FORCEPROP 2 LAST CDS_LIB standard
J 0
(-1975 4550);
DISPLAY INVISIBLE (-1975 4550);
FORCEADD OFFPAGE..1
R 2
(-1975 4450);
FORCEPROP 2 LAST $XR0 158 
J 0
(-1789 4450);
DISPLAY 0.638298 (-1789 4450);
PAINT MONO (-1789 4450);
FORCEPROP 2 LAST PATH I1237
J 0
(-1775 4500);
DISPLAY 0.680851 (-1775 4500);
DISPLAY INVISIBLE (-1775 4500);
FORCEPROP 2 LAST CDS_LIB standard
J 0
(-1975 4450);
DISPLAY INVISIBLE (-1975 4450);
FORCEPROP 1 LAST OFFPAGE TRUE
J 2
(-2300 4325);
DISPLAY 0.872340 (-2300 4325);
PAINT GREEN (-2300 4325);
DISPLAY INVISIBLE (-2300 4325);
FORCEPROP 1 LAST COMMENT_BODY TRUE
J 2
(-2100 4350);
DISPLAY 0.872340 (-2100 4350);
PAINT GREEN (-2100 4350);
DISPLAY INVISIBLE (-2100 4350);
FORCEADD OFFPAGE..1
R 2
(-1975 4500);
FORCEPROP 2 LAST $XR1 118 
J 0
(-1669 4500);
DISPLAY 0.638298 (-1669 4500);
PAINT MONO (-1669 4500);
FORCEPROP 2 LAST $XR0 117 
J 0
(-1789 4500);
DISPLAY 0.638298 (-1789 4500);
PAINT MONO (-1789 4500);
FORCEPROP 2 LAST PATH I1238
J 0
(-1775 4550);
DISPLAY 0.680851 (-1775 4550);
DISPLAY INVISIBLE (-1775 4550);
FORCEPROP 1 LAST COMMENT_BODY TRUE
J 2
(-2105 4400);
DISPLAY 1.106383 (-2105 4400);
PAINT PEACH (-2105 4400);
DISPLAY INVISIBLE (-2105 4400);
FORCEPROP 1 LAST OFFPAGE TRUE
J 2
(-2305 4370);
PAINT GREEN (-2305 4370);
DISPLAY INVISIBLE (-2305 4370);
FORCEPROP 2 LAST CDS_LIB standard
J 2
(-1975 4500);
DISPLAY INVISIBLE (-1975 4500);
FORCEADD OFFPAGE..1
R 2
(-1975 4400);
FORCEPROP 2 LAST $XR0 158 
J 0
(-1789 4400);
DISPLAY 0.638298 (-1789 4400);
PAINT MONO (-1789 4400);
FORCEPROP 2 LAST PATH I1239
J 0
(-1775 4450);
DISPLAY 0.680851 (-1775 4450);
DISPLAY INVISIBLE (-1775 4450);
FORCEPROP 2 LAST CDS_LIB standard
J 0
(-1975 4400);
DISPLAY INVISIBLE (-1975 4400);
FORCEPROP 1 LAST OFFPAGE TRUE
J 2
(-2300 4275);
DISPLAY 0.872340 (-2300 4275);
PAINT GREEN (-2300 4275);
DISPLAY INVISIBLE (-2300 4275);
FORCEPROP 1 LAST COMMENT_BODY TRUE
J 2
(-2100 4300);
DISPLAY 0.872340 (-2100 4300);
PAINT GREEN (-2100 4300);
DISPLAY INVISIBLE (-2100 4300);
FORCEADD OFFPAGE..2
(-1975 4350);
FORCEPROP 2 LAST $XR0 154 
J 0
(-1786 4350);
DISPLAY 0.638298 (-1786 4350);
PAINT MONO (-1786 4350);
FORCEPROP 2 LAST PATH I1240
J 0
(-1775 4400);
DISPLAY 0.680851 (-1775 4400);
DISPLAY INVISIBLE (-1775 4400);
FORCEPROP 2 LAST CDS_LIB standard
J 0
(-1975 4350);
DISPLAY INVISIBLE (-1975 4350);
FORCEPROP 1 LAST OFFPAGE TRUE
J 0
(-1650 4225);
DISPLAY 0.872340 (-1650 4225);
PAINT GREEN (-1650 4225);
DISPLAY INVISIBLE (-1650 4225);
FORCEPROP 1 LAST COMMENT_BODY TRUE
J 0
(-2020 4255);
DISPLAY 0.872340 (-2020 4255);
PAINT GREEN (-2020 4255);
DISPLAY INVISIBLE (-2020 4255);
FORCEADD OFFPAGE..2
(-1975 4300);
FORCEPROP 2 LAST $XR0 153 
J 0
(-1786 4300);
DISPLAY 0.638298 (-1786 4300);
PAINT MONO (-1786 4300);
FORCEPROP 2 LAST PATH I1241
J 0
(-1775 4350);
DISPLAY 0.680851 (-1775 4350);
DISPLAY INVISIBLE (-1775 4350);
FORCEPROP 2 LAST CDS_LIB standard
J 0
(-1975 4300);
DISPLAY INVISIBLE (-1975 4300);
FORCEPROP 1 LAST OFFPAGE TRUE
J 0
(-1650 4175);
DISPLAY 0.872340 (-1650 4175);
PAINT GREEN (-1650 4175);
DISPLAY INVISIBLE (-1650 4175);
FORCEPROP 1 LAST COMMENT_BODY TRUE
J 0
(-2020 4205);
DISPLAY 0.872340 (-2020 4205);
PAINT GREEN (-2020 4205);
DISPLAY INVISIBLE (-2020 4205);
FORCEADD OFFPAGE..2
(-1975 4200);
FORCEPROP 2 LAST $XR0 110 
J 0
(-1786 4200);
DISPLAY 0.638298 (-1786 4200);
PAINT MONO (-1786 4200);
FORCEPROP 2 LAST PATH I1242
J 0
(-1775 4250);
DISPLAY 0.680851 (-1775 4250);
DISPLAY INVISIBLE (-1775 4250);
FORCEPROP 2 LAST CDS_LIB standard
J 0
(-1975 4200);
DISPLAY INVISIBLE (-1975 4200);
FORCEPROP 1 LAST OFFPAGE TRUE
J 0
(-1650 4075);
DISPLAY 0.872340 (-1650 4075);
PAINT GREEN (-1650 4075);
DISPLAY INVISIBLE (-1650 4075);
FORCEPROP 1 LAST COMMENT_BODY TRUE
J 0
(-2020 4105);
DISPLAY 0.872340 (-2020 4105);
PAINT GREEN (-2020 4105);
DISPLAY INVISIBLE (-2020 4105);
FORCEADD OFFPAGE..2
(-1975 4250);
FORCEPROP 2 LAST $XR0 110 
J 0
(-1786 4250);
DISPLAY 0.638298 (-1786 4250);
PAINT MONO (-1786 4250);
FORCEPROP 2 LAST PATH I1243
J 0
(-1775 4300);
DISPLAY 0.680851 (-1775 4300);
DISPLAY INVISIBLE (-1775 4300);
FORCEPROP 2 LAST CDS_LIB standard
J 0
(-1975 4250);
DISPLAY INVISIBLE (-1975 4250);
FORCEPROP 1 LAST OFFPAGE TRUE
J 0
(-1650 4125);
DISPLAY 0.872340 (-1650 4125);
PAINT GREEN (-1650 4125);
DISPLAY INVISIBLE (-1650 4125);
FORCEPROP 1 LAST COMMENT_BODY TRUE
J 0
(-2020 4155);
DISPLAY 0.872340 (-2020 4155);
PAINT GREEN (-2020 4155);
DISPLAY INVISIBLE (-2020 4155);
FORCEADD OFFPAGE..2
(-1975 4100);
FORCEPROP 2 LAST $XR0 117 
J 0
(-1786 4100);
DISPLAY 0.638298 (-1786 4100);
PAINT MONO (-1786 4100);
FORCEPROP 2 LAST PATH I1244
J 0
(-1775 4150);
DISPLAY 0.680851 (-1775 4150);
DISPLAY INVISIBLE (-1775 4150);
FORCEPROP 2 LAST CDS_LIB standard
J 0
(-1975 4100);
DISPLAY INVISIBLE (-1975 4100);
FORCEPROP 1 LAST OFFPAGE TRUE
J 0
(-1650 3975);
DISPLAY 0.872340 (-1650 3975);
PAINT GREEN (-1650 3975);
DISPLAY INVISIBLE (-1650 3975);
FORCEPROP 1 LAST COMMENT_BODY TRUE
J 0
(-2020 4005);
DISPLAY 0.872340 (-2020 4005);
PAINT GREEN (-2020 4005);
DISPLAY INVISIBLE (-2020 4005);
FORCEADD OFFPAGE..2
(-1975 4050);
FORCEPROP 2 LAST $XR0 83 
J 0
(-1786 4050);
DISPLAY 0.638298 (-1786 4050);
PAINT MONO (-1786 4050);
FORCEPROP 2 LAST PATH I1245
J 0
(-1775 4100);
DISPLAY 0.680851 (-1775 4100);
DISPLAY INVISIBLE (-1775 4100);
FORCEPROP 2 LAST CDS_LIB standard
J 0
(-1975 4050);
DISPLAY INVISIBLE (-1975 4050);
FORCEPROP 1 LAST OFFPAGE TRUE
J 0
(-1650 3925);
DISPLAY 0.872340 (-1650 3925);
PAINT GREEN (-1650 3925);
DISPLAY INVISIBLE (-1650 3925);
FORCEPROP 1 LAST COMMENT_BODY TRUE
J 0
(-2020 3955);
DISPLAY 0.872340 (-2020 3955);
PAINT GREEN (-2020 3955);
DISPLAY INVISIBLE (-2020 3955);
FORCEADD OFFPAGE..2
(-1975 3950);
FORCEPROP 2 LAST $XR0 110 
J 0
(-1786 3950);
DISPLAY 0.638298 (-1786 3950);
PAINT MONO (-1786 3950);
FORCEPROP 2 LAST PATH I1246
J 0
(-1775 4000);
DISPLAY 0.680851 (-1775 4000);
DISPLAY INVISIBLE (-1775 4000);
FORCEPROP 2 LAST CDS_LIB standard
J 0
(-1975 3950);
DISPLAY INVISIBLE (-1975 3950);
FORCEPROP 1 LAST OFFPAGE TRUE
J 0
(-1650 3825);
DISPLAY 0.872340 (-1650 3825);
PAINT GREEN (-1650 3825);
DISPLAY INVISIBLE (-1650 3825);
FORCEPROP 1 LAST COMMENT_BODY TRUE
J 0
(-2020 3855);
DISPLAY 0.872340 (-2020 3855);
PAINT GREEN (-2020 3855);
DISPLAY INVISIBLE (-2020 3855);
FORCEADD OFFPAGE..2
(-1975 4000);
FORCEPROP 2 LAST $XR0 186 
J 0
(-1786 4000);
DISPLAY 0.638298 (-1786 4000);
PAINT MONO (-1786 4000);
FORCEPROP 2 LAST PATH I1247
J 0
(-1775 4050);
DISPLAY 0.680851 (-1775 4050);
DISPLAY INVISIBLE (-1775 4050);
FORCEPROP 2 LAST CDS_LIB standard
J 0
(-1975 4000);
DISPLAY INVISIBLE (-1975 4000);
FORCEPROP 1 LAST OFFPAGE TRUE
J 0
(-1650 3875);
DISPLAY 0.872340 (-1650 3875);
PAINT GREEN (-1650 3875);
DISPLAY INVISIBLE (-1650 3875);
FORCEPROP 1 LAST COMMENT_BODY TRUE
J 0
(-2020 3905);
DISPLAY 0.872340 (-2020 3905);
PAINT GREEN (-2020 3905);
DISPLAY INVISIBLE (-2020 3905);
FORCEADD OFFPAGE..2
(-1975 3900);
FORCEPROP 2 LAST $XR0 124 
J 0
(-1786 3900);
DISPLAY 0.638298 (-1786 3900);
PAINT MONO (-1786 3900);
FORCEPROP 2 LAST PATH I1248
J 0
(-1775 3950);
DISPLAY 0.680851 (-1775 3950);
DISPLAY INVISIBLE (-1775 3950);
FORCEPROP 2 LAST CDS_LIB standard
J 0
(-1975 3900);
DISPLAY INVISIBLE (-1975 3900);
FORCEPROP 1 LAST OFFPAGE TRUE
J 0
(-1650 3775);
DISPLAY 0.872340 (-1650 3775);
PAINT GREEN (-1650 3775);
DISPLAY INVISIBLE (-1650 3775);
FORCEPROP 1 LAST COMMENT_BODY TRUE
J 0
(-2020 3805);
DISPLAY 0.872340 (-2020 3805);
PAINT GREEN (-2020 3805);
DISPLAY INVISIBLE (-2020 3805);
FORCEADD OFFPAGE..2
(-1975 3850);
FORCEPROP 2 LAST $XR0 169 
J 0
(-1786 3850);
DISPLAY 0.638298 (-1786 3850);
PAINT MONO (-1786 3850);
FORCEPROP 2 LAST PATH I1249
J 0
(-1775 3900);
DISPLAY 0.680851 (-1775 3900);
DISPLAY INVISIBLE (-1775 3900);
FORCEPROP 2 LAST CDS_LIB standard
J 0
(-1975 3850);
DISPLAY INVISIBLE (-1975 3850);
FORCEPROP 1 LAST OFFPAGE TRUE
J 0
(-1650 3725);
DISPLAY 0.872340 (-1650 3725);
PAINT GREEN (-1650 3725);
DISPLAY INVISIBLE (-1650 3725);
FORCEPROP 1 LAST COMMENT_BODY TRUE
J 0
(-2020 3755);
DISPLAY 0.872340 (-2020 3755);
PAINT GREEN (-2020 3755);
DISPLAY INVISIBLE (-2020 3755);
FORCEADD OFFPAGE..2
(-1975 3800);
FORCEPROP 2 LAST $XR0 112 
J 0
(-1786 3800);
DISPLAY 0.638298 (-1786 3800);
PAINT MONO (-1786 3800);
FORCEPROP 2 LAST PATH I1250
J 0
(-1775 3850);
DISPLAY 0.680851 (-1775 3850);
DISPLAY INVISIBLE (-1775 3850);
FORCEPROP 2 LAST CDS_LIB standard
J 0
(-1975 3800);
DISPLAY INVISIBLE (-1975 3800);
FORCEPROP 1 LAST OFFPAGE TRUE
J 0
(-1650 3675);
DISPLAY 0.872340 (-1650 3675);
PAINT GREEN (-1650 3675);
DISPLAY INVISIBLE (-1650 3675);
FORCEPROP 1 LAST COMMENT_BODY TRUE
J 0
(-2020 3705);
DISPLAY 0.872340 (-2020 3705);
PAINT GREEN (-2020 3705);
DISPLAY INVISIBLE (-2020 3705);
FORCEADD OFFPAGE..1
R 2
(-1975 3700);
FORCEPROP 2 LAST $XR0 186 
J 0
(-1789 3700);
DISPLAY 0.638298 (-1789 3700);
PAINT MONO (-1789 3700);
FORCEPROP 2 LAST PATH I1251
J 0
(-1775 3750);
DISPLAY 0.680851 (-1775 3750);
DISPLAY INVISIBLE (-1775 3750);
FORCEPROP 2 LAST CDS_LIB standard
J 0
(-1975 3700);
DISPLAY INVISIBLE (-1975 3700);
FORCEPROP 1 LAST OFFPAGE TRUE
J 2
(-2300 3575);
DISPLAY 0.872340 (-2300 3575);
PAINT GREEN (-2300 3575);
DISPLAY INVISIBLE (-2300 3575);
FORCEPROP 1 LAST COMMENT_BODY TRUE
J 2
(-2100 3600);
DISPLAY 0.872340 (-2100 3600);
PAINT GREEN (-2100 3600);
DISPLAY INVISIBLE (-2100 3600);
FORCEADD OFFPAGE..2
(-1975 3750);
FORCEPROP 2 LAST $XR0 110 
J 0
(-1786 3750);
DISPLAY 0.638298 (-1786 3750);
PAINT MONO (-1786 3750);
FORCEPROP 2 LAST PATH I1252
J 0
(-1775 3800);
DISPLAY 0.680851 (-1775 3800);
DISPLAY INVISIBLE (-1775 3800);
FORCEPROP 2 LAST CDS_LIB standard
J 0
(-1975 3750);
DISPLAY INVISIBLE (-1975 3750);
FORCEPROP 1 LAST OFFPAGE TRUE
J 0
(-1650 3625);
DISPLAY 0.872340 (-1650 3625);
PAINT GREEN (-1650 3625);
DISPLAY INVISIBLE (-1650 3625);
FORCEPROP 1 LAST COMMENT_BODY TRUE
J 0
(-2020 3655);
DISPLAY 0.872340 (-2020 3655);
PAINT GREEN (-2020 3655);
DISPLAY INVISIBLE (-2020 3655);
FORCEADD OFFPAGE..2
(-1975 3650);
FORCEPROP 2 LAST $XR0 110 
J 0
(-1786 3650);
DISPLAY 0.638298 (-1786 3650);
PAINT MONO (-1786 3650);
FORCEPROP 2 LAST PATH I1253
J 0
(-1775 3700);
DISPLAY 0.680851 (-1775 3700);
DISPLAY INVISIBLE (-1775 3700);
FORCEPROP 2 LAST CDS_LIB standard
J 0
(-1975 3650);
DISPLAY INVISIBLE (-1975 3650);
FORCEPROP 1 LAST OFFPAGE TRUE
J 0
(-1650 3525);
DISPLAY 0.872340 (-1650 3525);
PAINT GREEN (-1650 3525);
DISPLAY INVISIBLE (-1650 3525);
FORCEPROP 1 LAST COMMENT_BODY TRUE
J 0
(-2020 3555);
DISPLAY 0.872340 (-2020 3555);
PAINT GREEN (-2020 3555);
DISPLAY INVISIBLE (-2020 3555);
FORCEADD OFFPAGE..2
(-1975 3600);
FORCEPROP 2 LAST $XR0 125 
J 0
(-1786 3600);
DISPLAY 0.638298 (-1786 3600);
PAINT MONO (-1786 3600);
FORCEPROP 2 LAST PATH I1254
J 0
(-1775 3650);
DISPLAY 0.680851 (-1775 3650);
DISPLAY INVISIBLE (-1775 3650);
FORCEPROP 2 LAST CDS_LIB standard
J 0
(-1975 3600);
DISPLAY INVISIBLE (-1975 3600);
FORCEPROP 1 LAST OFFPAGE TRUE
J 0
(-1650 3475);
DISPLAY 0.872340 (-1650 3475);
PAINT GREEN (-1650 3475);
DISPLAY INVISIBLE (-1650 3475);
FORCEPROP 1 LAST COMMENT_BODY TRUE
J 0
(-2020 3505);
DISPLAY 0.872340 (-2020 3505);
PAINT GREEN (-2020 3505);
DISPLAY INVISIBLE (-2020 3505);
FORCEADD OFFPAGE..2
(-1975 3450);
FORCEPROP 2 LAST $XR0 111 
J 0
(-1786 3450);
DISPLAY 0.638298 (-1786 3450);
PAINT MONO (-1786 3450);
FORCEPROP 2 LAST CDS_LIB standard
J 0
(-1975 3450);
DISPLAY INVISIBLE (-1975 3450);
FORCEPROP 2 LAST PATH I1256
J 0
(-1775 3500);
DISPLAY 0.680851 (-1775 3500);
DISPLAY INVISIBLE (-1775 3500);
FORCEPROP 1 LAST COMMENT_BODY TRUE
J 0
(-2020 3355);
DISPLAY 0.872340 (-2020 3355);
PAINT GREEN (-2020 3355);
DISPLAY INVISIBLE (-2020 3355);
FORCEPROP 1 LAST OFFPAGE TRUE
J 0
(-1650 3325);
DISPLAY 0.872340 (-1650 3325);
PAINT GREEN (-1650 3325);
DISPLAY INVISIBLE (-1650 3325);
FORCEADD OFFPAGE..2
(-1975 3500);
FORCEPROP 2 LAST $XR0 110 
J 0
(-1786 3500);
DISPLAY 0.638298 (-1786 3500);
PAINT MONO (-1786 3500);
FORCEPROP 2 LAST PATH I1257
J 0
(-1775 3550);
DISPLAY 0.680851 (-1775 3550);
DISPLAY INVISIBLE (-1775 3550);
FORCEPROP 2 LAST CDS_LIB standard
J 0
(-1975 3500);
DISPLAY INVISIBLE (-1975 3500);
FORCEPROP 1 LAST OFFPAGE TRUE
J 0
(-1650 3375);
DISPLAY 0.872340 (-1650 3375);
PAINT GREEN (-1650 3375);
DISPLAY INVISIBLE (-1650 3375);
FORCEPROP 1 LAST COMMENT_BODY TRUE
J 0
(-2020 3405);
DISPLAY 0.872340 (-2020 3405);
PAINT GREEN (-2020 3405);
DISPLAY INVISIBLE (-2020 3405);
FORCEADD OFFPAGE..2
(-1975 3250);
FORCEPROP 2 LAST $XR0 112 
J 0
(-1786 3250);
DISPLAY 0.638298 (-1786 3250);
PAINT MONO (-1786 3250);
FORCEPROP 2 LAST PATH I1258
J 0
(-1775 3300);
DISPLAY 0.680851 (-1775 3300);
DISPLAY INVISIBLE (-1775 3300);
FORCEPROP 1 LAST COMMENT_BODY TRUE
J 0
(-2020 3155);
DISPLAY 0.872340 (-2020 3155);
PAINT GREEN (-2020 3155);
DISPLAY INVISIBLE (-2020 3155);
FORCEPROP 1 LAST OFFPAGE TRUE
J 0
(-1650 3125);
DISPLAY 0.872340 (-1650 3125);
PAINT GREEN (-1650 3125);
DISPLAY INVISIBLE (-1650 3125);
FORCEPROP 2 LAST CDS_LIB standard
J 0
(-1975 3250);
DISPLAY INVISIBLE (-1975 3250);
FORCEADD OFFPAGE..2
(-1975 3150);
FORCEPROP 2 LAST $XR0 110 
J 0
(-1786 3150);
DISPLAY 0.638298 (-1786 3150);
PAINT MONO (-1786 3150);
FORCEPROP 2 LAST PATH I1259
J 0
(-1775 3200);
DISPLAY 0.680851 (-1775 3200);
DISPLAY INVISIBLE (-1775 3200);
FORCEPROP 1 LAST COMMENT_BODY TRUE
J 0
(-2020 3055);
DISPLAY 0.872340 (-2020 3055);
PAINT GREEN (-2020 3055);
DISPLAY INVISIBLE (-2020 3055);
FORCEPROP 1 LAST OFFPAGE TRUE
J 0
(-1650 3025);
DISPLAY 0.872340 (-1650 3025);
PAINT GREEN (-1650 3025);
DISPLAY INVISIBLE (-1650 3025);
FORCEPROP 2 LAST CDS_LIB standard
J 0
(-1975 3150);
DISPLAY INVISIBLE (-1975 3150);
FORCEADD OFFPAGE..3
(-1975 3100);
FORCEPROP 2 LAST $XR0 118 
J 0
(-1761 3100);
DISPLAY 0.638298 (-1761 3100);
PAINT MONO (-1761 3100);
FORCEPROP 2 LAST PATH I1260
J 0
(-1750 3150);
DISPLAY 0.680851 (-1750 3150);
DISPLAY INVISIBLE (-1750 3150);
FORCEPROP 1 LAST COMMENT_BODY TRUE
J 0
(-2025 3000);
DISPLAY 0.872340 (-2025 3000);
PAINT GREEN (-2025 3000);
DISPLAY INVISIBLE (-2025 3000);
FORCEPROP 1 LAST OFFPAGE TRUE
J 0
(-1650 2975);
DISPLAY 0.872340 (-1650 2975);
PAINT GREEN (-1650 2975);
DISPLAY INVISIBLE (-1650 2975);
FORCEPROP 2 LAST CDS_LIB standard
J 2
(-1975 3100);
DISPLAY INVISIBLE (-1975 3100);
FORCEADD OFFPAGE..2
(-1975 3000);
FORCEPROP 2 LAST $XR0 111 
J 0
(-1786 3000);
DISPLAY 0.638298 (-1786 3000);
PAINT MONO (-1786 3000);
FORCEPROP 2 LAST PATH I1261
J 0
(-1775 3050);
DISPLAY 0.680851 (-1775 3050);
DISPLAY INVISIBLE (-1775 3050);
FORCEPROP 1 LAST COMMENT_BODY TRUE
J 0
(-2020 2905);
DISPLAY 0.872340 (-2020 2905);
PAINT GREEN (-2020 2905);
DISPLAY INVISIBLE (-2020 2905);
FORCEPROP 1 LAST OFFPAGE TRUE
J 0
(-1650 2875);
DISPLAY 0.872340 (-1650 2875);
PAINT GREEN (-1650 2875);
DISPLAY INVISIBLE (-1650 2875);
FORCEPROP 2 LAST CDS_LIB standard
J 0
(-1975 3000);
DISPLAY INVISIBLE (-1975 3000);
FORCEADD Q_RES..1
R 2
(-2975 4950);
FORCEPROP 1 LAST LOCATION R51
J 0
(-3175 4950);
DISPLAY 0.489362 (-3175 4950);
PAINT SKYBLUE (-3175 4950);
FORCEPROP 0 LAST $SEC 1
J 0
(-3025 5000);
DISPLAY 0.680851 (-3025 5000);
PAINT MONO (-3025 5000);
DISPLAY INVISIBLE (-3025 5000);
FORCEPROP 0 LAST CDS_SEC 1
J 0
(-3025 5000);
DISPLAY 1.021277 (-3025 5000);
DISPLAY INVISIBLE (-3025 5000);
FORCEPROP 1 LASTPIN (-2875 4950) $PN 1
J 2
(-2887 4962);
DISPLAY 0.489362 (-2887 4962);
PAINT MONO (-2887 4962);
FORCEPROP 1 LASTPIN (-3075 4950) $PN 2
J 2
(-3060 4960);
DISPLAY 0.489362 (-3060 4960);
PAINT MONO (-3060 4960);
FORCEPROP 1 LAST VALUE 0
J 0
(-2850 4950);
DISPLAY 0.489362 (-2850 4950);
PAINT SKYBLUE (-2850 4950);
FORCEPROP 2 LAST CDS_LIB pure_quanta
J 0
(-2975 4950);
DISPLAY INVISIBLE (-2975 4950);
FORCEPROP 2 LAST BOM_COST MEM
J 0
(-3000 5100);
DISPLAY 0.744681 (-3000 5100);
PAINT WHITE (-3000 5100);
DISPLAY INVISIBLE (-3000 5100);
FORCEPROP 1 LAST PATH I1262
J 2
(-2925 5100);
DISPLAY 0.978723 (-2925 5100);
PAINT WHITE (-2925 5100);
DISPLAY INVISIBLE (-2925 5100);
FORCEPROP 1 LAST WATTAGE 1/16W
J 0
(-2900 4875);
DISPLAY 0.489362 (-2900 4875);
PAINT SKYBLUE (-2900 4875);
DISPLAY INVISIBLE (-2900 4875);
FORCEPROP 1 LAST MATERIAL CHIP
J 0
(-3150 4925);
DISPLAY 0.489362 (-3150 4925);
PAINT SKYBLUE (-3150 4925);
DISPLAY INVISIBLE (-3150 4925);
FORCEPROP 1 LAST TOLERANCE 5%
J 2
(-2850 4925);
DISPLAY 0.489362 (-2850 4925);
PAINT SKYBLUE (-2850 4925);
DISPLAY INVISIBLE (-2850 4925);
FORCEPROP 1 LAST PART_NUMBER CS00002JB38
J 0
(-3075 5000);
DISPLAY 0.489362 (-3075 5000);
PAINT SKYBLUE (-3075 5000);
DISPLAY INVISIBLE (-3075 5000);
FORCEPROP 1 LAST PACK_TYPE 0402LF
J 0
(-3150 4875);
DISPLAY 0.489362 (-3150 4875);
PAINT SKYBLUE (-3150 4875);
DISPLAY INVISIBLE (-3150 4875);
FORCEPROP 2 LAST ROOM RST_CPU0_PLD_TO_DIMM
J 0
(-3000 5050);
DISPLAY 0.744681 (-3000 5050);
PAINT RED (-3000 5050);
DISPLAY INVISIBLE (-3000 5050);
FORCEADD Q_RES..1
R 2
(-2975 4900);
FORCEPROP 1 LAST LOCATION R56
J 0
(-3175 4900);
DISPLAY 0.489362 (-3175 4900);
PAINT SKYBLUE (-3175 4900);
FORCEPROP 0 LAST $SEC 1
J 0
(-3025 4950);
DISPLAY 0.680851 (-3025 4950);
PAINT MONO (-3025 4950);
DISPLAY INVISIBLE (-3025 4950);
FORCEPROP 0 LAST CDS_SEC 1
J 0
(-3025 4950);
DISPLAY 1.021277 (-3025 4950);
DISPLAY INVISIBLE (-3025 4950);
FORCEPROP 1 LASTPIN (-2875 4900) $PN 1
J 2
(-2887 4912);
DISPLAY 0.489362 (-2887 4912);
PAINT MONO (-2887 4912);
FORCEPROP 1 LASTPIN (-3075 4900) $PN 2
J 2
(-3060 4910);
DISPLAY 0.489362 (-3060 4910);
PAINT MONO (-3060 4910);
FORCEPROP 1 LAST VALUE 0
J 0
(-2850 4900);
DISPLAY 0.489362 (-2850 4900);
PAINT SKYBLUE (-2850 4900);
FORCEPROP 2 LAST CDS_LIB pure_quanta
J 0
(-2975 4900);
DISPLAY INVISIBLE (-2975 4900);
FORCEPROP 2 LAST BOM_COST MEM
J 0
(-3000 5050);
DISPLAY 0.744681 (-3000 5050);
PAINT WHITE (-3000 5050);
DISPLAY INVISIBLE (-3000 5050);
FORCEPROP 1 LAST PATH I1263
J 2
(-2925 5050);
DISPLAY 0.978723 (-2925 5050);
PAINT WHITE (-2925 5050);
DISPLAY INVISIBLE (-2925 5050);
FORCEPROP 1 LAST WATTAGE 1/16W
J 0
(-2900 4825);
DISPLAY 0.489362 (-2900 4825);
PAINT SKYBLUE (-2900 4825);
DISPLAY INVISIBLE (-2900 4825);
FORCEPROP 1 LAST MATERIAL CHIP
J 0
(-3150 4875);
DISPLAY 0.489362 (-3150 4875);
PAINT SKYBLUE (-3150 4875);
DISPLAY INVISIBLE (-3150 4875);
FORCEPROP 1 LAST TOLERANCE 5%
J 2
(-2850 4875);
DISPLAY 0.489362 (-2850 4875);
PAINT SKYBLUE (-2850 4875);
DISPLAY INVISIBLE (-2850 4875);
FORCEPROP 1 LAST PART_NUMBER CS00002JB38
J 0
(-3075 4950);
DISPLAY 0.489362 (-3075 4950);
PAINT SKYBLUE (-3075 4950);
DISPLAY INVISIBLE (-3075 4950);
FORCEPROP 1 LAST PACK_TYPE 0402LF
J 0
(-3150 4825);
DISPLAY 0.489362 (-3150 4825);
PAINT SKYBLUE (-3150 4825);
DISPLAY INVISIBLE (-3150 4825);
FORCEPROP 2 LAST ROOM RST_CPU0_PLD_TO_DIMM
J 0
(-3000 5000);
DISPLAY 0.744681 (-3000 5000);
PAINT RED (-3000 5000);
DISPLAY INVISIBLE (-3000 5000);
FORCEADD Q_RES..1
(-2975 4850);
FORCEPROP 1 LAST LOCATION R1056
J 0
(-3175 4850);
DISPLAY 0.489362 (-3175 4850);
PAINT SKYBLUE (-3175 4850);
FORCEPROP 0 LAST $SEC 1
J 0
(-2800 4875);
DISPLAY 0.680851 (-2800 4875);
PAINT MONO (-2800 4875);
DISPLAY INVISIBLE (-2800 4875);
FORCEPROP 0 LAST CDS_SEC 1
J 0
(-2800 4875);
DISPLAY 0.680851 (-2800 4875);
DISPLAY INVISIBLE (-2800 4875);
FORCEPROP 1 LASTPIN (-3075 4850) $PN 1
J 0
(-3063 4862);
DISPLAY 0.489362 (-3063 4862);
PAINT MONO (-3063 4862);
FORCEPROP 1 LASTPIN (-2875 4850) $PN 2
J 0
(-2913 4862);
DISPLAY 0.489362 (-2913 4862);
PAINT MONO (-2913 4862);
FORCEPROP 1 LAST VALUE 33
J 2
(-2800 4850);
DISPLAY 0.489362 (-2800 4850);
PAINT SKYBLUE (-2800 4850);
FORCEPROP 2 LAST BOM_COST OCP3.0 
J 0
(-2900 4950);
DISPLAY 0.680851 (-2900 4950);
DISPLAY INVISIBLE (-2900 4950);
FORCEPROP 2 LAST CDS_LIB pure_quanta
J 0
(-2975 4850);
DISPLAY INVISIBLE (-2975 4850);
FORCEPROP 1 LAST PATH I1264
J 0
(-3025 5000);
DISPLAY 0.978723 (-3025 5000);
PAINT WHITE (-3025 5000);
DISPLAY INVISIBLE (-3025 5000);
FORCEPROP 1 LAST WATTAGE 1/16W
J 2
(-3000 4750);
DISPLAY 0.489362 (-3000 4750);
PAINT SKYBLUE (-3000 4750);
DISPLAY INVISIBLE (-3000 4750);
FORCEPROP 1 LAST MATERIAL CHIP
J 0
(-2825 4850);
DISPLAY 0.489362 (-2825 4850);
PAINT SKYBLUE (-2825 4850);
DISPLAY INVISIBLE (-2825 4850);
FORCEPROP 1 LAST TOLERANCE 5%
J 0
(-2975 4800);
DISPLAY 0.489362 (-2975 4800);
PAINT SKYBLUE (-2975 4800);
DISPLAY INVISIBLE (-2975 4800);
FORCEPROP 1 LAST PART_NUMBER CS03302JB29
J 0
(-2900 4900);
DISPLAY 0.489362 (-2900 4900);
PAINT SKYBLUE (-2900 4900);
DISPLAY INVISIBLE (-2900 4900);
FORCEPROP 1 LAST PACK_TYPE 0402LF
J 0
(-2900 4800);
DISPLAY 0.489362 (-2900 4800);
PAINT SKYBLUE (-2900 4800);
DISPLAY INVISIBLE (-2900 4800);
FORCEADD Q_RES..1
(-2975 4800);
FORCEPROP 1 LAST LOCATION R869
J 0
(-3175 4800);
DISPLAY 0.489362 (-3175 4800);
PAINT SKYBLUE (-3175 4800);
FORCEPROP 2 LAST $SEC 1
J 0
(-3025 5000);
DISPLAY 0.680851 (-3025 5000);
PAINT MONO (-3025 5000);
DISPLAY INVISIBLE (-3025 5000);
FORCEPROP 2 LAST CDS_SEC 1
J 0
(-3025 5000);
DISPLAY 0.680851 (-3025 5000);
DISPLAY INVISIBLE (-3025 5000);
FORCEPROP 1 LASTPIN (-3075 4800) $PN 1
J 0
(-3063 4812);
DISPLAY 0.489362 (-3063 4812);
PAINT MONO (-3063 4812);
FORCEPROP 1 LASTPIN (-2875 4800) $PN 2
J 0
(-2913 4812);
DISPLAY 0.489362 (-2913 4812);
PAINT MONO (-2913 4812);
FORCEPROP 1 LAST VALUE 33
J 2
(-2800 4800);
DISPLAY 0.489362 (-2800 4800);
PAINT SKYBLUE (-2800 4800);
FORCEPROP 2 LAST CDS_LIB pure_quanta
J 0
(-2975 4800);
DISPLAY INVISIBLE (-2975 4800);
FORCEPROP 2 LAST BOM_COST OCP3.0 
J 0
(-2900 4900);
DISPLAY 0.680851 (-2900 4900);
DISPLAY INVISIBLE (-2900 4900);
FORCEPROP 1 LAST PATH I1265
J 0
(-3025 4950);
DISPLAY 0.978723 (-3025 4950);
PAINT WHITE (-3025 4950);
DISPLAY INVISIBLE (-3025 4950);
FORCEPROP 1 LAST WATTAGE 1/16W
J 2
(-3000 4700);
DISPLAY 0.489362 (-3000 4700);
PAINT SKYBLUE (-3000 4700);
DISPLAY INVISIBLE (-3000 4700);
FORCEPROP 1 LAST MATERIAL CHIP
J 0
(-2825 4800);
DISPLAY 0.489362 (-2825 4800);
PAINT SKYBLUE (-2825 4800);
DISPLAY INVISIBLE (-2825 4800);
FORCEPROP 1 LAST TOLERANCE 5%
J 0
(-2975 4750);
DISPLAY 0.489362 (-2975 4750);
PAINT SKYBLUE (-2975 4750);
DISPLAY INVISIBLE (-2975 4750);
FORCEPROP 1 LAST PART_NUMBER CS03302JB29
J 0
(-2900 4850);
DISPLAY 0.489362 (-2900 4850);
PAINT SKYBLUE (-2900 4850);
DISPLAY INVISIBLE (-2900 4850);
FORCEPROP 1 LAST PACK_TYPE 0402LF
J 0
(-2900 4750);
DISPLAY 0.489362 (-2900 4750);
PAINT SKYBLUE (-2900 4750);
DISPLAY INVISIBLE (-2900 4750);
FORCEADD Q_RES..1
R 2
(-2975 4750);
FORCEPROP 1 LAST LOCATION R1268
J 0
(-3175 4750);
DISPLAY 0.489362 (-3175 4750);
PAINT SKYBLUE (-3175 4750);
FORCEPROP 0 LAST $SEC 1
J 0
(-3025 4800);
DISPLAY 0.680851 (-3025 4800);
PAINT MONO (-3025 4800);
DISPLAY INVISIBLE (-3025 4800);
FORCEPROP 0 LAST CDS_SEC 1
J 0
(-3025 4800);
DISPLAY 1.021277 (-3025 4800);
DISPLAY INVISIBLE (-3025 4800);
FORCEPROP 1 LASTPIN (-2875 4750) $PN 1
J 2
(-2887 4762);
DISPLAY 0.489362 (-2887 4762);
PAINT MONO (-2887 4762);
FORCEPROP 1 LASTPIN (-3075 4750) $PN 2
J 2
(-3060 4760);
DISPLAY 0.489362 (-3060 4760);
PAINT MONO (-3060 4760);
FORCEPROP 1 LAST VALUE 33
J 0
(-2850 4750);
DISPLAY 0.489362 (-2850 4750);
PAINT SKYBLUE (-2850 4750);
FORCEPROP 2 LAST CDS_LIB pure_quanta
J 0
(-2975 4750);
DISPLAY INVISIBLE (-2975 4750);
FORCEPROP 2 LAST BOM_COST MEM
J 0
(-3000 4900);
DISPLAY 0.744681 (-3000 4900);
PAINT WHITE (-3000 4900);
DISPLAY INVISIBLE (-3000 4900);
FORCEPROP 1 LAST PATH I1266
J 2
(-2925 4900);
DISPLAY 0.978723 (-2925 4900);
PAINT WHITE (-2925 4900);
DISPLAY INVISIBLE (-2925 4900);
FORCEPROP 1 LAST WATTAGE 1/16W
J 0
(-2900 4675);
DISPLAY 0.489362 (-2900 4675);
PAINT SKYBLUE (-2900 4675);
DISPLAY INVISIBLE (-2900 4675);
FORCEPROP 1 LAST MATERIAL CHIP
J 0
(-3150 4725);
DISPLAY 0.489362 (-3150 4725);
PAINT SKYBLUE (-3150 4725);
DISPLAY INVISIBLE (-3150 4725);
FORCEPROP 1 LAST TOLERANCE 5%
J 2
(-2850 4725);
DISPLAY 0.489362 (-2850 4725);
PAINT SKYBLUE (-2850 4725);
DISPLAY INVISIBLE (-2850 4725);
FORCEPROP 1 LAST PART_NUMBER CS03302JB29
J 0
(-3075 4800);
DISPLAY 0.489362 (-3075 4800);
PAINT SKYBLUE (-3075 4800);
DISPLAY INVISIBLE (-3075 4800);
FORCEPROP 1 LAST PACK_TYPE 0402LF
J 0
(-3150 4675);
DISPLAY 0.489362 (-3150 4675);
PAINT SKYBLUE (-3150 4675);
DISPLAY INVISIBLE (-3150 4675);
FORCEPROP 2 LAST ROOM RST_CPU0_PLD_TO_DIMM
J 0
(-3000 4850);
DISPLAY 0.744681 (-3000 4850);
PAINT RED (-3000 4850);
DISPLAY INVISIBLE (-3000 4850);
FORCEADD Q_RES..1
R 2
(-2975 4600);
FORCEPROP 1 LAST LOCATION R211
J 0
(-3175 4600);
DISPLAY 0.489362 (-3175 4600);
PAINT SKYBLUE (-3175 4600);
FORCEPROP 0 LAST $SEC 1
J 0
(-3025 4650);
DISPLAY 0.680851 (-3025 4650);
PAINT MONO (-3025 4650);
DISPLAY INVISIBLE (-3025 4650);
FORCEPROP 0 LAST CDS_SEC 1
J 0
(-3025 4650);
DISPLAY 1.021277 (-3025 4650);
DISPLAY INVISIBLE (-3025 4650);
FORCEPROP 1 LASTPIN (-2875 4600) $PN 1
J 2
(-2887 4612);
DISPLAY 0.489362 (-2887 4612);
PAINT MONO (-2887 4612);
FORCEPROP 1 LASTPIN (-3075 4600) $PN 2
J 2
(-3060 4610);
DISPLAY 0.489362 (-3060 4610);
PAINT MONO (-3060 4610);
FORCEPROP 1 LAST VALUE 0
J 0
(-2850 4600);
DISPLAY 0.489362 (-2850 4600);
PAINT SKYBLUE (-2850 4600);
FORCEPROP 2 LAST BOM_COST MEM
J 0
(-3000 4750);
DISPLAY 0.744681 (-3000 4750);
PAINT WHITE (-3000 4750);
DISPLAY INVISIBLE (-3000 4750);
FORCEPROP 2 LAST CDS_LIB pure_quanta
J 0
(-2975 4600);
DISPLAY INVISIBLE (-2975 4600);
FORCEPROP 1 LAST PATH I1267
J 2
(-2925 4750);
DISPLAY 0.978723 (-2925 4750);
PAINT WHITE (-2925 4750);
DISPLAY INVISIBLE (-2925 4750);
FORCEPROP 1 LAST WATTAGE 1/16W
J 0
(-2900 4525);
DISPLAY 0.489362 (-2900 4525);
PAINT SKYBLUE (-2900 4525);
DISPLAY INVISIBLE (-2900 4525);
FORCEPROP 1 LAST MATERIAL CHIP
J 0
(-3150 4575);
DISPLAY 0.489362 (-3150 4575);
PAINT SKYBLUE (-3150 4575);
DISPLAY INVISIBLE (-3150 4575);
FORCEPROP 1 LAST TOLERANCE 5%
J 2
(-2850 4575);
DISPLAY 0.489362 (-2850 4575);
PAINT SKYBLUE (-2850 4575);
DISPLAY INVISIBLE (-2850 4575);
FORCEPROP 1 LAST PART_NUMBER CS00002JB38
J 0
(-3075 4650);
DISPLAY 0.489362 (-3075 4650);
PAINT SKYBLUE (-3075 4650);
DISPLAY INVISIBLE (-3075 4650);
FORCEPROP 1 LAST PACK_TYPE 0402LF
J 0
(-3150 4525);
DISPLAY 0.489362 (-3150 4525);
PAINT SKYBLUE (-3150 4525);
DISPLAY INVISIBLE (-3150 4525);
FORCEPROP 2 LAST ROOM RST_CPU0_PLD_TO_DIMM
J 0
(-3000 4700);
DISPLAY 0.744681 (-3000 4700);
PAINT RED (-3000 4700);
DISPLAY INVISIBLE (-3000 4700);
FORCEADD Q_RES..1
R 2
(-2975 4650);
FORCEPROP 1 LAST LOCATION R210
J 0
(-3175 4650);
DISPLAY 0.489362 (-3175 4650);
PAINT SKYBLUE (-3175 4650);
FORCEPROP 0 LAST $SEC 1
J 0
(-3025 4700);
DISPLAY 0.680851 (-3025 4700);
PAINT MONO (-3025 4700);
DISPLAY INVISIBLE (-3025 4700);
FORCEPROP 0 LAST CDS_SEC 1
J 0
(-3025 4700);
DISPLAY 1.021277 (-3025 4700);
DISPLAY INVISIBLE (-3025 4700);
FORCEPROP 1 LASTPIN (-2875 4650) $PN 1
J 2
(-2887 4662);
DISPLAY 0.489362 (-2887 4662);
PAINT MONO (-2887 4662);
FORCEPROP 1 LASTPIN (-3075 4650) $PN 2
J 2
(-3060 4660);
DISPLAY 0.489362 (-3060 4660);
PAINT MONO (-3060 4660);
FORCEPROP 1 LAST VALUE 0
J 0
(-2850 4650);
DISPLAY 0.489362 (-2850 4650);
PAINT SKYBLUE (-2850 4650);
FORCEPROP 2 LAST BOM_COST MEM
J 0
(-3000 4800);
DISPLAY 0.744681 (-3000 4800);
PAINT WHITE (-3000 4800);
DISPLAY INVISIBLE (-3000 4800);
FORCEPROP 2 LAST CDS_LIB pure_quanta
J 0
(-2975 4650);
DISPLAY INVISIBLE (-2975 4650);
FORCEPROP 1 LAST PATH I1268
J 2
(-2925 4800);
DISPLAY 0.978723 (-2925 4800);
PAINT WHITE (-2925 4800);
DISPLAY INVISIBLE (-2925 4800);
FORCEPROP 1 LAST WATTAGE 1/16W
J 0
(-2900 4575);
DISPLAY 0.489362 (-2900 4575);
PAINT SKYBLUE (-2900 4575);
DISPLAY INVISIBLE (-2900 4575);
FORCEPROP 1 LAST MATERIAL CHIP
J 0
(-3150 4625);
DISPLAY 0.489362 (-3150 4625);
PAINT SKYBLUE (-3150 4625);
DISPLAY INVISIBLE (-3150 4625);
FORCEPROP 1 LAST TOLERANCE 5%
J 2
(-2850 4625);
DISPLAY 0.489362 (-2850 4625);
PAINT SKYBLUE (-2850 4625);
DISPLAY INVISIBLE (-2850 4625);
FORCEPROP 1 LAST PART_NUMBER CS00002JB38
J 0
(-3075 4700);
DISPLAY 0.489362 (-3075 4700);
PAINT SKYBLUE (-3075 4700);
DISPLAY INVISIBLE (-3075 4700);
FORCEPROP 1 LAST PACK_TYPE 0402LF
J 0
(-3150 4575);
DISPLAY 0.489362 (-3150 4575);
PAINT SKYBLUE (-3150 4575);
DISPLAY INVISIBLE (-3150 4575);
FORCEPROP 2 LAST ROOM RST_CPU0_PLD_TO_DIMM
J 0
(-3000 4750);
DISPLAY 0.744681 (-3000 4750);
PAINT RED (-3000 4750);
DISPLAY INVISIBLE (-3000 4750);
FORCEADD Q_RES..1
R 2
(-2975 4200);
FORCEPROP 1 LAST LOCATION R1273
J 0
(-3175 4200);
DISPLAY 0.489362 (-3175 4200);
PAINT SKYBLUE (-3175 4200);
FORCEPROP 0 LAST $SEC 1
J 0
(-3025 4250);
DISPLAY 0.680851 (-3025 4250);
PAINT MONO (-3025 4250);
DISPLAY INVISIBLE (-3025 4250);
FORCEPROP 0 LAST CDS_SEC 1
J 0
(-3025 4250);
DISPLAY 1.021277 (-3025 4250);
DISPLAY INVISIBLE (-3025 4250);
FORCEPROP 1 LASTPIN (-2875 4200) $PN 1
J 2
(-2887 4212);
DISPLAY 0.489362 (-2887 4212);
PAINT MONO (-2887 4212);
FORCEPROP 1 LASTPIN (-3075 4200) $PN 2
J 2
(-3060 4210);
DISPLAY 0.489362 (-3060 4210);
PAINT MONO (-3060 4210);
FORCEPROP 1 LAST VALUE 33
J 0
(-2850 4200);
DISPLAY 0.489362 (-2850 4200);
PAINT SKYBLUE (-2850 4200);
FORCEPROP 2 LAST CDS_LIB pure_quanta
J 0
(-2975 4200);
DISPLAY INVISIBLE (-2975 4200);
FORCEPROP 2 LAST BOM_COST MEM
J 0
(-3000 4350);
DISPLAY 0.744681 (-3000 4350);
PAINT WHITE (-3000 4350);
DISPLAY INVISIBLE (-3000 4350);
FORCEPROP 1 LAST PATH I1269
J 2
(-2925 4350);
DISPLAY 0.978723 (-2925 4350);
PAINT WHITE (-2925 4350);
DISPLAY INVISIBLE (-2925 4350);
FORCEPROP 1 LAST WATTAGE 1/16W
J 0
(-2900 4125);
DISPLAY 0.489362 (-2900 4125);
PAINT SKYBLUE (-2900 4125);
DISPLAY INVISIBLE (-2900 4125);
FORCEPROP 1 LAST MATERIAL CHIP
J 0
(-3150 4175);
DISPLAY 0.489362 (-3150 4175);
PAINT SKYBLUE (-3150 4175);
DISPLAY INVISIBLE (-3150 4175);
FORCEPROP 1 LAST TOLERANCE 5%
J 2
(-2850 4175);
DISPLAY 0.489362 (-2850 4175);
PAINT SKYBLUE (-2850 4175);
DISPLAY INVISIBLE (-2850 4175);
FORCEPROP 1 LAST PART_NUMBER CS03302JB29
J 0
(-3075 4250);
DISPLAY 0.489362 (-3075 4250);
PAINT SKYBLUE (-3075 4250);
DISPLAY INVISIBLE (-3075 4250);
FORCEPROP 1 LAST PACK_TYPE 0402LF
J 0
(-3150 4125);
DISPLAY 0.489362 (-3150 4125);
PAINT SKYBLUE (-3150 4125);
DISPLAY INVISIBLE (-3150 4125);
FORCEPROP 2 LAST ROOM RST_CPU0_PLD_TO_DIMM
J 0
(-3000 4300);
DISPLAY 0.744681 (-3000 4300);
PAINT RED (-3000 4300);
DISPLAY INVISIBLE (-3000 4300);
FORCEADD Q_RES..1
R 2
(-2975 4250);
FORCEPROP 1 LAST LOCATION R1272
J 0
(-3175 4250);
DISPLAY 0.489362 (-3175 4250);
PAINT SKYBLUE (-3175 4250);
FORCEPROP 0 LAST $SEC 1
J 0
(-3025 4300);
DISPLAY 0.680851 (-3025 4300);
PAINT MONO (-3025 4300);
DISPLAY INVISIBLE (-3025 4300);
FORCEPROP 0 LAST CDS_SEC 1
J 0
(-3025 4300);
DISPLAY 1.021277 (-3025 4300);
DISPLAY INVISIBLE (-3025 4300);
FORCEPROP 1 LASTPIN (-2875 4250) $PN 1
J 2
(-2887 4262);
DISPLAY 0.489362 (-2887 4262);
PAINT MONO (-2887 4262);
FORCEPROP 1 LASTPIN (-3075 4250) $PN 2
J 2
(-3060 4260);
DISPLAY 0.489362 (-3060 4260);
PAINT MONO (-3060 4260);
FORCEPROP 1 LAST VALUE 33
J 0
(-2850 4250);
DISPLAY 0.489362 (-2850 4250);
PAINT SKYBLUE (-2850 4250);
FORCEPROP 2 LAST CDS_LIB pure_quanta
J 0
(-2975 4250);
DISPLAY INVISIBLE (-2975 4250);
FORCEPROP 2 LAST BOM_COST MEM
J 0
(-3000 4400);
DISPLAY 0.744681 (-3000 4400);
PAINT WHITE (-3000 4400);
DISPLAY INVISIBLE (-3000 4400);
FORCEPROP 1 LAST PATH I1270
J 2
(-2925 4400);
DISPLAY 0.978723 (-2925 4400);
PAINT WHITE (-2925 4400);
DISPLAY INVISIBLE (-2925 4400);
FORCEPROP 1 LAST WATTAGE 1/16W
J 0
(-2900 4175);
DISPLAY 0.489362 (-2900 4175);
PAINT SKYBLUE (-2900 4175);
DISPLAY INVISIBLE (-2900 4175);
FORCEPROP 1 LAST MATERIAL CHIP
J 0
(-3150 4225);
DISPLAY 0.489362 (-3150 4225);
PAINT SKYBLUE (-3150 4225);
DISPLAY INVISIBLE (-3150 4225);
FORCEPROP 1 LAST TOLERANCE 5%
J 2
(-2850 4225);
DISPLAY 0.489362 (-2850 4225);
PAINT SKYBLUE (-2850 4225);
DISPLAY INVISIBLE (-2850 4225);
FORCEPROP 1 LAST PART_NUMBER CS03302JB29
J 0
(-3075 4300);
DISPLAY 0.489362 (-3075 4300);
PAINT SKYBLUE (-3075 4300);
DISPLAY INVISIBLE (-3075 4300);
FORCEPROP 1 LAST PACK_TYPE 0402LF
J 0
(-3150 4175);
DISPLAY 0.489362 (-3150 4175);
PAINT SKYBLUE (-3150 4175);
DISPLAY INVISIBLE (-3150 4175);
FORCEPROP 2 LAST ROOM RST_CPU0_PLD_TO_DIMM
J 0
(-3000 4350);
DISPLAY 0.744681 (-3000 4350);
PAINT RED (-3000 4350);
DISPLAY INVISIBLE (-3000 4350);
FORCEADD Q_RES..1
R 2
(-2975 4100);
FORCEPROP 1 LAST LOCATION R63
J 0
(-3175 4100);
DISPLAY 0.489362 (-3175 4100);
PAINT SKYBLUE (-3175 4100);
FORCEPROP 0 LAST $SEC 1
J 0
(-3100 4150);
DISPLAY 0.680851 (-3100 4150);
PAINT MONO (-3100 4150);
DISPLAY INVISIBLE (-3100 4150);
FORCEPROP 0 LAST CDS_SEC 1
J 0
(-3100 4150);
DISPLAY 1.021277 (-3100 4150);
DISPLAY INVISIBLE (-3100 4150);
FORCEPROP 1 LASTPIN (-2875 4100) $PN 1
J 2
(-2887 4112);
DISPLAY 0.489362 (-2887 4112);
PAINT MONO (-2887 4112);
FORCEPROP 1 LASTPIN (-3075 4100) $PN 2
J 2
(-3037 4112);
DISPLAY 0.489362 (-3037 4112);
PAINT MONO (-3037 4112);
FORCEPROP 1 LAST VALUE 33
J 0
(-2850 4100);
DISPLAY 0.489362 (-2850 4100);
PAINT SKYBLUE (-2850 4100);
FORCEPROP 2 LAST BOM_COST MEM
J 0
(-3000 4250);
DISPLAY 0.744681 (-3000 4250);
PAINT WHITE (-3000 4250);
DISPLAY INVISIBLE (-3000 4250);
FORCEPROP 2 LAST CDS_LIB pure_quanta
J 0
(-2975 4100);
DISPLAY INVISIBLE (-2975 4100);
FORCEPROP 1 LAST PATH I1271
J 2
(-2925 4250);
DISPLAY 0.978723 (-2925 4250);
PAINT WHITE (-2925 4250);
DISPLAY INVISIBLE (-2925 4250);
FORCEPROP 1 LAST WATTAGE 1/16W
J 0
(-2900 4025);
DISPLAY 0.489362 (-2900 4025);
PAINT SKYBLUE (-2900 4025);
DISPLAY INVISIBLE (-2900 4025);
FORCEPROP 1 LAST MATERIAL CHIP
J 0
(-3150 4075);
DISPLAY 0.489362 (-3150 4075);
PAINT SKYBLUE (-3150 4075);
DISPLAY INVISIBLE (-3150 4075);
FORCEPROP 1 LAST TOLERANCE 5%
J 2
(-2850 4075);
DISPLAY 0.489362 (-2850 4075);
PAINT SKYBLUE (-2850 4075);
DISPLAY INVISIBLE (-2850 4075);
FORCEPROP 1 LAST PART_NUMBER CS03302JB29
J 0
(-3075 4150);
DISPLAY 0.489362 (-3075 4150);
PAINT SKYBLUE (-3075 4150);
DISPLAY INVISIBLE (-3075 4150);
FORCEPROP 1 LAST PACK_TYPE 0402LF
J 0
(-3150 4025);
DISPLAY 0.489362 (-3150 4025);
PAINT SKYBLUE (-3150 4025);
DISPLAY INVISIBLE (-3150 4025);
FORCEPROP 2 LAST ROOM RST_CPU0_PLD_TO_DIMM
J 0
(-3000 4200);
DISPLAY 0.744681 (-3000 4200);
PAINT RED (-3000 4200);
DISPLAY INVISIBLE (-3000 4200);
FORCEADD Q_RES..1
R 2
(-2975 3950);
FORCEPROP 1 LAST LOCATION R1269
J 0
(-3175 3950);
DISPLAY 0.489362 (-3175 3950);
PAINT SKYBLUE (-3175 3950);
FORCEPROP 0 LAST $SEC 1
J 0
(-3025 4000);
DISPLAY 0.680851 (-3025 4000);
PAINT MONO (-3025 4000);
DISPLAY INVISIBLE (-3025 4000);
FORCEPROP 0 LAST CDS_SEC 1
J 0
(-3025 4000);
DISPLAY 1.021277 (-3025 4000);
DISPLAY INVISIBLE (-3025 4000);
FORCEPROP 1 LASTPIN (-2875 3950) $PN 1
J 2
(-2887 3962);
DISPLAY 0.489362 (-2887 3962);
PAINT MONO (-2887 3962);
FORCEPROP 1 LASTPIN (-3075 3950) $PN 2
J 2
(-3060 3960);
DISPLAY 0.489362 (-3060 3960);
PAINT MONO (-3060 3960);
FORCEPROP 1 LAST VALUE 33
J 0
(-2850 3950);
DISPLAY 0.489362 (-2850 3950);
PAINT SKYBLUE (-2850 3950);
FORCEPROP 2 LAST BOM_COST MEM
J 0
(-3000 4100);
DISPLAY 0.744681 (-3000 4100);
PAINT WHITE (-3000 4100);
DISPLAY INVISIBLE (-3000 4100);
FORCEPROP 2 LAST CDS_LIB pure_quanta
J 0
(-2975 3950);
DISPLAY INVISIBLE (-2975 3950);
FORCEPROP 1 LAST PATH I1272
J 2
(-2925 4100);
DISPLAY 0.978723 (-2925 4100);
PAINT WHITE (-2925 4100);
DISPLAY INVISIBLE (-2925 4100);
FORCEPROP 1 LAST WATTAGE 1/16W
J 0
(-2900 3875);
DISPLAY 0.489362 (-2900 3875);
PAINT SKYBLUE (-2900 3875);
DISPLAY INVISIBLE (-2900 3875);
FORCEPROP 1 LAST MATERIAL CHIP
J 0
(-3150 3925);
DISPLAY 0.489362 (-3150 3925);
PAINT SKYBLUE (-3150 3925);
DISPLAY INVISIBLE (-3150 3925);
FORCEPROP 1 LAST TOLERANCE 5%
J 2
(-2850 3925);
DISPLAY 0.489362 (-2850 3925);
PAINT SKYBLUE (-2850 3925);
DISPLAY INVISIBLE (-2850 3925);
FORCEPROP 1 LAST PART_NUMBER CS03302JB29
J 0
(-3075 4000);
DISPLAY 0.489362 (-3075 4000);
PAINT SKYBLUE (-3075 4000);
DISPLAY INVISIBLE (-3075 4000);
FORCEPROP 1 LAST PACK_TYPE 0402LF
J 0
(-3150 3875);
DISPLAY 0.489362 (-3150 3875);
PAINT SKYBLUE (-3150 3875);
DISPLAY INVISIBLE (-3150 3875);
FORCEPROP 2 LAST ROOM RST_CPU0_PLD_TO_DIMM
J 0
(-3000 4050);
DISPLAY 0.744681 (-3000 4050);
PAINT RED (-3000 4050);
DISPLAY INVISIBLE (-3000 4050);
FORCEADD Q_RES..1
(-2975 3900);
FORCEPROP 1 LAST LOCATION R704
J 0
(-3175 3900);
DISPLAY 0.489362 (-3175 3900);
PAINT SKYBLUE (-3175 3900);
FORCEPROP 2 LAST $SEC 1
J 0
(-3025 4100);
DISPLAY 0.680851 (-3025 4100);
PAINT MONO (-3025 4100);
DISPLAY INVISIBLE (-3025 4100);
FORCEPROP 2 LAST CDS_SEC 1
J 0
(-3025 4100);
DISPLAY 0.680851 (-3025 4100);
DISPLAY INVISIBLE (-3025 4100);
FORCEPROP 1 LASTPIN (-3075 3900) $PN 1
J 0
(-3063 3912);
DISPLAY 0.489362 (-3063 3912);
PAINT MONO (-3063 3912);
FORCEPROP 1 LASTPIN (-2875 3900) $PN 2
J 0
(-2913 3912);
DISPLAY 0.489362 (-2913 3912);
PAINT MONO (-2913 3912);
FORCEPROP 1 LAST VALUE 33
J 2
(-2800 3900);
DISPLAY 0.489362 (-2800 3900);
PAINT SKYBLUE (-2800 3900);
FORCEPROP 2 LAST BOM_COST OCP3.0 
J 0
(-2900 4000);
DISPLAY 0.680851 (-2900 4000);
DISPLAY INVISIBLE (-2900 4000);
FORCEPROP 2 LAST CDS_LIB pure_quanta
J 0
(-2975 3900);
DISPLAY INVISIBLE (-2975 3900);
FORCEPROP 1 LAST PATH I1273
J 0
(-3025 4050);
DISPLAY 0.978723 (-3025 4050);
PAINT WHITE (-3025 4050);
DISPLAY INVISIBLE (-3025 4050);
FORCEPROP 1 LAST WATTAGE 1/16W
J 2
(-3000 3800);
DISPLAY 0.489362 (-3000 3800);
PAINT SKYBLUE (-3000 3800);
DISPLAY INVISIBLE (-3000 3800);
FORCEPROP 1 LAST MATERIAL CHIP
J 0
(-2825 3900);
DISPLAY 0.489362 (-2825 3900);
PAINT SKYBLUE (-2825 3900);
DISPLAY INVISIBLE (-2825 3900);
FORCEPROP 1 LAST TOLERANCE 5%
J 0
(-2975 3850);
DISPLAY 0.489362 (-2975 3850);
PAINT SKYBLUE (-2975 3850);
DISPLAY INVISIBLE (-2975 3850);
FORCEPROP 1 LAST PART_NUMBER CS03302JB29
J 0
(-2900 3950);
DISPLAY 0.489362 (-2900 3950);
PAINT SKYBLUE (-2900 3950);
DISPLAY INVISIBLE (-2900 3950);
FORCEPROP 1 LAST PACK_TYPE 0402LF
J 0
(-2900 3850);
DISPLAY 0.489362 (-2900 3850);
PAINT SKYBLUE (-2900 3850);
DISPLAY INVISIBLE (-2900 3850);
FORCEADD Q_RES..1
R 2
(-2975 3800);
FORCEPROP 1 LAST LOCATION R1276
J 0
(-3175 3800);
DISPLAY 0.489362 (-3175 3800);
PAINT SKYBLUE (-3175 3800);
FORCEPROP 0 LAST $SEC 1
J 0
(-3025 3850);
DISPLAY 0.680851 (-3025 3850);
PAINT MONO (-3025 3850);
DISPLAY INVISIBLE (-3025 3850);
FORCEPROP 0 LAST CDS_SEC 1
J 0
(-3025 3850);
DISPLAY 1.021277 (-3025 3850);
DISPLAY INVISIBLE (-3025 3850);
FORCEPROP 1 LASTPIN (-2875 3800) $PN 1
J 2
(-2887 3812);
DISPLAY 0.489362 (-2887 3812);
PAINT MONO (-2887 3812);
FORCEPROP 1 LASTPIN (-3075 3800) $PN 2
J 2
(-3060 3810);
DISPLAY 0.489362 (-3060 3810);
PAINT MONO (-3060 3810);
FORCEPROP 1 LAST VALUE 33
J 0
(-2850 3800);
DISPLAY 0.489362 (-2850 3800);
PAINT SKYBLUE (-2850 3800);
FORCEPROP 2 LAST BOM_COST MEM
J 0
(-3000 3950);
DISPLAY 0.744681 (-3000 3950);
PAINT WHITE (-3000 3950);
DISPLAY INVISIBLE (-3000 3950);
FORCEPROP 2 LAST CDS_LIB pure_quanta
J 0
(-2975 3800);
DISPLAY INVISIBLE (-2975 3800);
FORCEPROP 1 LAST PATH I1274
J 2
(-2925 3950);
DISPLAY 0.978723 (-2925 3950);
PAINT WHITE (-2925 3950);
DISPLAY INVISIBLE (-2925 3950);
FORCEPROP 1 LAST WATTAGE 1/16W
J 0
(-2900 3725);
DISPLAY 0.489362 (-2900 3725);
PAINT SKYBLUE (-2900 3725);
DISPLAY INVISIBLE (-2900 3725);
FORCEPROP 1 LAST MATERIAL CHIP
J 0
(-3150 3775);
DISPLAY 0.489362 (-3150 3775);
PAINT SKYBLUE (-3150 3775);
DISPLAY INVISIBLE (-3150 3775);
FORCEPROP 1 LAST TOLERANCE 5%
J 2
(-2850 3775);
DISPLAY 0.489362 (-2850 3775);
PAINT SKYBLUE (-2850 3775);
DISPLAY INVISIBLE (-2850 3775);
FORCEPROP 1 LAST PART_NUMBER CS03302JB29
J 0
(-3075 3850);
DISPLAY 0.489362 (-3075 3850);
PAINT SKYBLUE (-3075 3850);
DISPLAY INVISIBLE (-3075 3850);
FORCEPROP 1 LAST PACK_TYPE 0402LF
J 0
(-3150 3725);
DISPLAY 0.489362 (-3150 3725);
PAINT SKYBLUE (-3150 3725);
DISPLAY INVISIBLE (-3150 3725);
FORCEPROP 2 LAST ROOM RST_CPU0_PLD_TO_DIMM
J 0
(-3000 3900);
DISPLAY 0.744681 (-3000 3900);
PAINT RED (-3000 3900);
DISPLAY INVISIBLE (-3000 3900);
FORCEADD Q_RES..1
R 2
(-2975 3650);
FORCEPROP 1 LAST LOCATION R1267
J 0
(-3175 3650);
DISPLAY 0.489362 (-3175 3650);
PAINT SKYBLUE (-3175 3650);
FORCEPROP 0 LAST $SEC 1
J 0
(-3025 3700);
DISPLAY 0.680851 (-3025 3700);
PAINT MONO (-3025 3700);
DISPLAY INVISIBLE (-3025 3700);
FORCEPROP 0 LAST CDS_SEC 1
J 0
(-3025 3700);
DISPLAY 1.021277 (-3025 3700);
DISPLAY INVISIBLE (-3025 3700);
FORCEPROP 1 LASTPIN (-2875 3650) $PN 1
J 2
(-2887 3662);
DISPLAY 0.489362 (-2887 3662);
PAINT MONO (-2887 3662);
FORCEPROP 1 LASTPIN (-3075 3650) $PN 2
J 2
(-3060 3660);
DISPLAY 0.489362 (-3060 3660);
PAINT MONO (-3060 3660);
FORCEPROP 1 LAST VALUE 33
J 0
(-2850 3650);
DISPLAY 0.489362 (-2850 3650);
PAINT SKYBLUE (-2850 3650);
FORCEPROP 2 LAST CDS_LIB pure_quanta
J 0
(-2975 3650);
DISPLAY INVISIBLE (-2975 3650);
FORCEPROP 2 LAST BOM_COST MEM
J 0
(-3000 3800);
DISPLAY 0.744681 (-3000 3800);
PAINT WHITE (-3000 3800);
DISPLAY INVISIBLE (-3000 3800);
FORCEPROP 1 LAST PATH I1275
J 2
(-2925 3800);
DISPLAY 0.978723 (-2925 3800);
PAINT WHITE (-2925 3800);
DISPLAY INVISIBLE (-2925 3800);
FORCEPROP 1 LAST WATTAGE 1/16W
J 0
(-2900 3575);
DISPLAY 0.489362 (-2900 3575);
PAINT SKYBLUE (-2900 3575);
DISPLAY INVISIBLE (-2900 3575);
FORCEPROP 1 LAST MATERIAL CHIP
J 0
(-3150 3625);
DISPLAY 0.489362 (-3150 3625);
PAINT SKYBLUE (-3150 3625);
DISPLAY INVISIBLE (-3150 3625);
FORCEPROP 1 LAST TOLERANCE 5%
J 2
(-2850 3625);
DISPLAY 0.489362 (-2850 3625);
PAINT SKYBLUE (-2850 3625);
DISPLAY INVISIBLE (-2850 3625);
FORCEPROP 1 LAST PART_NUMBER CS03302JB29
J 0
(-3075 3700);
DISPLAY 0.489362 (-3075 3700);
PAINT SKYBLUE (-3075 3700);
DISPLAY INVISIBLE (-3075 3700);
FORCEPROP 1 LAST PACK_TYPE 0402LF
J 0
(-3150 3575);
DISPLAY 0.489362 (-3150 3575);
PAINT SKYBLUE (-3150 3575);
DISPLAY INVISIBLE (-3150 3575);
FORCEPROP 2 LAST ROOM RST_CPU0_PLD_TO_DIMM
J 0
(-3000 3750);
DISPLAY 0.744681 (-3000 3750);
PAINT RED (-3000 3750);
DISPLAY INVISIBLE (-3000 3750);
FORCEADD Q_RES..1
R 2
(-2975 3750);
FORCEPROP 1 LAST LOCATION R1271
J 0
(-3175 3750);
DISPLAY 0.489362 (-3175 3750);
PAINT SKYBLUE (-3175 3750);
FORCEPROP 0 LAST $SEC 1
J 0
(-3025 3800);
DISPLAY 0.680851 (-3025 3800);
PAINT MONO (-3025 3800);
DISPLAY INVISIBLE (-3025 3800);
FORCEPROP 0 LAST CDS_SEC 1
J 0
(-3025 3800);
DISPLAY 1.021277 (-3025 3800);
DISPLAY INVISIBLE (-3025 3800);
FORCEPROP 1 LASTPIN (-2875 3750) $PN 1
J 2
(-2887 3762);
DISPLAY 0.489362 (-2887 3762);
PAINT MONO (-2887 3762);
FORCEPROP 1 LASTPIN (-3075 3750) $PN 2
J 2
(-3060 3760);
DISPLAY 0.489362 (-3060 3760);
PAINT MONO (-3060 3760);
FORCEPROP 1 LAST VALUE 33
J 0
(-2850 3750);
DISPLAY 0.489362 (-2850 3750);
PAINT SKYBLUE (-2850 3750);
FORCEPROP 2 LAST CDS_LIB pure_quanta
J 0
(-2975 3750);
DISPLAY INVISIBLE (-2975 3750);
FORCEPROP 2 LAST BOM_COST MEM
J 0
(-3000 3900);
DISPLAY 0.744681 (-3000 3900);
PAINT WHITE (-3000 3900);
DISPLAY INVISIBLE (-3000 3900);
FORCEPROP 1 LAST PATH I1276
J 2
(-2925 3900);
DISPLAY 0.978723 (-2925 3900);
PAINT WHITE (-2925 3900);
DISPLAY INVISIBLE (-2925 3900);
FORCEPROP 1 LAST WATTAGE 1/16W
J 0
(-2900 3675);
DISPLAY 0.489362 (-2900 3675);
PAINT SKYBLUE (-2900 3675);
DISPLAY INVISIBLE (-2900 3675);
FORCEPROP 1 LAST MATERIAL CHIP
J 0
(-3150 3725);
DISPLAY 0.489362 (-3150 3725);
PAINT SKYBLUE (-3150 3725);
DISPLAY INVISIBLE (-3150 3725);
FORCEPROP 1 LAST TOLERANCE 5%
J 2
(-2850 3725);
DISPLAY 0.489362 (-2850 3725);
PAINT SKYBLUE (-2850 3725);
DISPLAY INVISIBLE (-2850 3725);
FORCEPROP 1 LAST PART_NUMBER CS03302JB29
J 0
(-3075 3800);
DISPLAY 0.489362 (-3075 3800);
PAINT SKYBLUE (-3075 3800);
DISPLAY INVISIBLE (-3075 3800);
FORCEPROP 1 LAST PACK_TYPE 0402LF
J 0
(-3150 3675);
DISPLAY 0.489362 (-3150 3675);
PAINT SKYBLUE (-3150 3675);
DISPLAY INVISIBLE (-3150 3675);
FORCEPROP 2 LAST ROOM RST_CPU0_PLD_TO_DIMM
J 0
(-3000 3850);
DISPLAY 0.744681 (-3000 3850);
PAINT RED (-3000 3850);
DISPLAY INVISIBLE (-3000 3850);
FORCEADD Q_RES..1
(-2975 3600);
FORCEPROP 1 LAST LOCATION R1040
J 0
(-3175 3600);
DISPLAY 0.489362 (-3175 3600);
PAINT SKYBLUE (-3175 3600);
FORCEPROP 2 LAST $SEC 1
J 0
(-3025 3800);
DISPLAY 0.680851 (-3025 3800);
PAINT MONO (-3025 3800);
DISPLAY INVISIBLE (-3025 3800);
FORCEPROP 2 LAST CDS_SEC 1
J 0
(-3025 3800);
DISPLAY 0.680851 (-3025 3800);
DISPLAY INVISIBLE (-3025 3800);
FORCEPROP 1 LASTPIN (-3075 3600) $PN 1
J 0
(-3063 3612);
DISPLAY 0.489362 (-3063 3612);
PAINT MONO (-3063 3612);
FORCEPROP 1 LASTPIN (-2875 3600) $PN 2
J 0
(-2913 3612);
DISPLAY 0.489362 (-2913 3612);
PAINT MONO (-2913 3612);
FORCEPROP 1 LAST VALUE 33
J 2
(-2800 3600);
DISPLAY 0.489362 (-2800 3600);
PAINT SKYBLUE (-2800 3600);
FORCEPROP 2 LAST BOM_COST OCP3.0 
J 0
(-2900 3700);
DISPLAY 0.680851 (-2900 3700);
DISPLAY INVISIBLE (-2900 3700);
FORCEPROP 2 LAST CDS_LIB pure_quanta
J 0
(-2975 3600);
DISPLAY INVISIBLE (-2975 3600);
FORCEPROP 1 LAST PATH I1277
J 0
(-3025 3750);
DISPLAY 0.978723 (-3025 3750);
PAINT WHITE (-3025 3750);
DISPLAY INVISIBLE (-3025 3750);
FORCEPROP 1 LAST WATTAGE 1/16W
J 2
(-3000 3500);
DISPLAY 0.489362 (-3000 3500);
PAINT SKYBLUE (-3000 3500);
DISPLAY INVISIBLE (-3000 3500);
FORCEPROP 1 LAST MATERIAL CHIP
J 0
(-2825 3600);
DISPLAY 0.489362 (-2825 3600);
PAINT SKYBLUE (-2825 3600);
DISPLAY INVISIBLE (-2825 3600);
FORCEPROP 1 LAST TOLERANCE 5%
J 0
(-2975 3550);
DISPLAY 0.489362 (-2975 3550);
PAINT SKYBLUE (-2975 3550);
DISPLAY INVISIBLE (-2975 3550);
FORCEPROP 1 LAST PART_NUMBER CS03302JB29
J 0
(-2900 3650);
DISPLAY 0.489362 (-2900 3650);
PAINT SKYBLUE (-2900 3650);
DISPLAY INVISIBLE (-2900 3650);
FORCEPROP 1 LAST PACK_TYPE 0402LF
J 0
(-2900 3550);
DISPLAY 0.489362 (-2900 3550);
PAINT SKYBLUE (-2900 3550);
DISPLAY INVISIBLE (-2900 3550);
FORCEADD Q_RES..1
R 2
(-2975 3500);
FORCEPROP 1 LAST LOCATION R1254
J 0
(-3175 3500);
DISPLAY 0.489362 (-3175 3500);
PAINT SKYBLUE (-3175 3500);
FORCEPROP 0 LAST $SEC 1
J 0
(-3025 3550);
DISPLAY 0.680851 (-3025 3550);
PAINT MONO (-3025 3550);
DISPLAY INVISIBLE (-3025 3550);
FORCEPROP 0 LAST CDS_SEC 1
J 0
(-3025 3550);
DISPLAY 1.021277 (-3025 3550);
DISPLAY INVISIBLE (-3025 3550);
FORCEPROP 1 LASTPIN (-2875 3500) $PN 1
J 2
(-2887 3512);
DISPLAY 0.489362 (-2887 3512);
PAINT MONO (-2887 3512);
FORCEPROP 1 LASTPIN (-3075 3500) $PN 2
J 2
(-3060 3510);
DISPLAY 0.489362 (-3060 3510);
PAINT MONO (-3060 3510);
FORCEPROP 1 LAST VALUE 33
J 2
(-2800 3500);
DISPLAY 0.489362 (-2800 3500);
PAINT SKYBLUE (-2800 3500);
FORCEPROP 2 LAST CDS_LIB pure_quanta
J 0
(-2975 3500);
DISPLAY INVISIBLE (-2975 3500);
FORCEPROP 2 LAST BOM_COST MEM
J 0
(-3000 3650);
DISPLAY 0.744681 (-3000 3650);
PAINT WHITE (-3000 3650);
DISPLAY INVISIBLE (-3000 3650);
FORCEPROP 1 LAST PATH I1278
J 2
(-2925 3650);
DISPLAY 0.978723 (-2925 3650);
PAINT WHITE (-2925 3650);
DISPLAY INVISIBLE (-2925 3650);
FORCEPROP 1 LAST WATTAGE 1/16W
J 0
(-2900 3425);
DISPLAY 0.489362 (-2900 3425);
PAINT SKYBLUE (-2900 3425);
DISPLAY INVISIBLE (-2900 3425);
FORCEPROP 1 LAST MATERIAL CHIP
J 0
(-3150 3475);
DISPLAY 0.489362 (-3150 3475);
PAINT SKYBLUE (-3150 3475);
DISPLAY INVISIBLE (-3150 3475);
FORCEPROP 1 LAST TOLERANCE 5%
J 2
(-2850 3475);
DISPLAY 0.489362 (-2850 3475);
PAINT SKYBLUE (-2850 3475);
DISPLAY INVISIBLE (-2850 3475);
FORCEPROP 1 LAST PART_NUMBER CS03302JB29
J 0
(-3075 3550);
DISPLAY 0.489362 (-3075 3550);
PAINT SKYBLUE (-3075 3550);
DISPLAY INVISIBLE (-3075 3550);
FORCEPROP 1 LAST PACK_TYPE 0402LF
J 0
(-3150 3425);
DISPLAY 0.489362 (-3150 3425);
PAINT SKYBLUE (-3150 3425);
DISPLAY INVISIBLE (-3150 3425);
FORCEPROP 2 LAST ROOM RST_CPU0_PLD_TO_DIMM
J 0
(-3000 3600);
DISPLAY 0.744681 (-3000 3600);
PAINT RED (-3000 3600);
DISPLAY INVISIBLE (-3000 3600);
FORCEADD Q_RES..1
R 2
(-2975 3450);
FORCEPROP 1 LAST LOCATION R1274
J 0
(-3175 3450);
DISPLAY 0.489362 (-3175 3450);
PAINT SKYBLUE (-3175 3450);
FORCEPROP 0 LAST $SEC 1
J 0
(-3025 3500);
DISPLAY 0.680851 (-3025 3500);
PAINT MONO (-3025 3500);
DISPLAY INVISIBLE (-3025 3500);
FORCEPROP 0 LAST CDS_SEC 1
J 0
(-3025 3500);
DISPLAY 1.021277 (-3025 3500);
DISPLAY INVISIBLE (-3025 3500);
FORCEPROP 1 LASTPIN (-2875 3450) $PN 1
J 2
(-2887 3462);
DISPLAY 0.489362 (-2887 3462);
PAINT MONO (-2887 3462);
FORCEPROP 1 LASTPIN (-3075 3450) $PN 2
J 2
(-3060 3460);
DISPLAY 0.489362 (-3060 3460);
PAINT MONO (-3060 3460);
FORCEPROP 1 LAST VALUE 33
J 0
(-2850 3450);
DISPLAY 0.489362 (-2850 3450);
PAINT SKYBLUE (-2850 3450);
FORCEPROP 2 LAST CDS_LIB pure_quanta
J 0
(-2975 3450);
DISPLAY INVISIBLE (-2975 3450);
FORCEPROP 1 LAST PATH I1279
J 2
(-2925 3600);
DISPLAY 0.978723 (-2925 3600);
PAINT WHITE (-2925 3600);
DISPLAY INVISIBLE (-2925 3600);
FORCEPROP 2 LAST ROOM RST_CPU0_PLD_TO_DIMM
J 0
(-3000 3550);
DISPLAY 0.744681 (-3000 3550);
PAINT RED (-3000 3550);
DISPLAY INVISIBLE (-3000 3550);
FORCEPROP 1 LAST PACK_TYPE 0402LF
J 0
(-3150 3375);
DISPLAY 0.489362 (-3150 3375);
PAINT SKYBLUE (-3150 3375);
DISPLAY INVISIBLE (-3150 3375);
FORCEPROP 1 LAST PART_NUMBER CS03302JB29
J 0
(-3075 3500);
DISPLAY 0.489362 (-3075 3500);
PAINT SKYBLUE (-3075 3500);
DISPLAY INVISIBLE (-3075 3500);
FORCEPROP 1 LAST TOLERANCE 5%
J 2
(-2850 3425);
DISPLAY 0.489362 (-2850 3425);
PAINT SKYBLUE (-2850 3425);
DISPLAY INVISIBLE (-2850 3425);
FORCEPROP 1 LAST MATERIAL CHIP
J 0
(-3150 3425);
DISPLAY 0.489362 (-3150 3425);
PAINT SKYBLUE (-3150 3425);
DISPLAY INVISIBLE (-3150 3425);
FORCEPROP 1 LAST WATTAGE 1/16W
J 0
(-2900 3375);
DISPLAY 0.489362 (-2900 3375);
PAINT SKYBLUE (-2900 3375);
DISPLAY INVISIBLE (-2900 3375);
FORCEPROP 2 LAST BOM_COST MEM
J 0
(-3000 3600);
DISPLAY 0.744681 (-3000 3600);
PAINT WHITE (-3000 3600);
DISPLAY INVISIBLE (-3000 3600);
FORCEADD Q_RES..1
R 2
(-2975 3150);
FORCEPROP 1 LAST LOCATION R1270
J 0
(-3175 3150);
DISPLAY 0.489362 (-3175 3150);
PAINT SKYBLUE (-3175 3150);
FORCEPROP 0 LAST $SEC 1
J 0
(-3025 3200);
DISPLAY 0.680851 (-3025 3200);
PAINT MONO (-3025 3200);
DISPLAY INVISIBLE (-3025 3200);
FORCEPROP 0 LAST CDS_SEC 1
J 0
(-3025 3200);
DISPLAY 1.021277 (-3025 3200);
DISPLAY INVISIBLE (-3025 3200);
FORCEPROP 1 LASTPIN (-2875 3150) $PN 1
J 2
(-2887 3162);
DISPLAY 0.489362 (-2887 3162);
PAINT MONO (-2887 3162);
FORCEPROP 1 LASTPIN (-3075 3150) $PN 2
J 2
(-3060 3160);
DISPLAY 0.489362 (-3060 3160);
PAINT MONO (-3060 3160);
FORCEPROP 1 LAST VALUE 33
J 0
(-2850 3150);
DISPLAY 0.489362 (-2850 3150);
PAINT SKYBLUE (-2850 3150);
FORCEPROP 2 LAST CDS_LIB pure_quanta
J 0
(-2975 3150);
DISPLAY INVISIBLE (-2975 3150);
FORCEPROP 2 LAST BOM_COST MEM
J 0
(-3000 3300);
DISPLAY 0.744681 (-3000 3300);
PAINT WHITE (-3000 3300);
DISPLAY INVISIBLE (-3000 3300);
FORCEPROP 1 LAST PATH I1280
J 2
(-2925 3300);
DISPLAY 0.978723 (-2925 3300);
PAINT WHITE (-2925 3300);
DISPLAY INVISIBLE (-2925 3300);
FORCEPROP 1 LAST WATTAGE 1/16W
J 0
(-2900 3075);
DISPLAY 0.489362 (-2900 3075);
PAINT SKYBLUE (-2900 3075);
DISPLAY INVISIBLE (-2900 3075);
FORCEPROP 1 LAST MATERIAL CHIP
J 0
(-3150 3125);
DISPLAY 0.489362 (-3150 3125);
PAINT SKYBLUE (-3150 3125);
DISPLAY INVISIBLE (-3150 3125);
FORCEPROP 1 LAST TOLERANCE 5%
J 2
(-2850 3125);
DISPLAY 0.489362 (-2850 3125);
PAINT SKYBLUE (-2850 3125);
DISPLAY INVISIBLE (-2850 3125);
FORCEPROP 1 LAST PART_NUMBER CS03302JB29
J 0
(-3075 3200);
DISPLAY 0.489362 (-3075 3200);
PAINT SKYBLUE (-3075 3200);
DISPLAY INVISIBLE (-3075 3200);
FORCEPROP 1 LAST PACK_TYPE 0402LF
J 0
(-3150 3075);
DISPLAY 0.489362 (-3150 3075);
PAINT SKYBLUE (-3150 3075);
DISPLAY INVISIBLE (-3150 3075);
FORCEPROP 2 LAST ROOM RST_CPU0_PLD_TO_DIMM
J 0
(-3000 3250);
DISPLAY 0.744681 (-3000 3250);
PAINT RED (-3000 3250);
DISPLAY INVISIBLE (-3000 3250);
FORCEADD Q_RES..1
R 2
(-2975 3250);
FORCEPROP 1 LAST LOCATION R1277
J 0
(-3175 3250);
DISPLAY 0.489362 (-3175 3250);
PAINT SKYBLUE (-3175 3250);
FORCEPROP 0 LAST $SEC 1
J 0
(-3025 3300);
DISPLAY 0.680851 (-3025 3300);
PAINT MONO (-3025 3300);
DISPLAY INVISIBLE (-3025 3300);
FORCEPROP 0 LAST CDS_SEC 1
J 0
(-3025 3300);
DISPLAY 1.021277 (-3025 3300);
DISPLAY INVISIBLE (-3025 3300);
FORCEPROP 1 LASTPIN (-2875 3250) $PN 1
J 2
(-2887 3262);
DISPLAY 0.489362 (-2887 3262);
PAINT MONO (-2887 3262);
FORCEPROP 1 LASTPIN (-3075 3250) $PN 2
J 2
(-3060 3260);
DISPLAY 0.489362 (-3060 3260);
PAINT MONO (-3060 3260);
FORCEPROP 1 LAST VALUE 33
J 0
(-2850 3250);
DISPLAY 0.489362 (-2850 3250);
PAINT SKYBLUE (-2850 3250);
FORCEPROP 2 LAST CDS_LIB pure_quanta
J 0
(-2975 3250);
DISPLAY INVISIBLE (-2975 3250);
FORCEPROP 2 LAST BOM_COST MEM
J 0
(-3000 3400);
DISPLAY 0.744681 (-3000 3400);
PAINT WHITE (-3000 3400);
DISPLAY INVISIBLE (-3000 3400);
FORCEPROP 1 LAST PATH I1281
J 2
(-2925 3400);
DISPLAY 0.978723 (-2925 3400);
PAINT WHITE (-2925 3400);
DISPLAY INVISIBLE (-2925 3400);
FORCEPROP 1 LAST WATTAGE 1/16W
J 0
(-2900 3175);
DISPLAY 0.489362 (-2900 3175);
PAINT SKYBLUE (-2900 3175);
DISPLAY INVISIBLE (-2900 3175);
FORCEPROP 1 LAST MATERIAL CHIP
J 0
(-3150 3225);
DISPLAY 0.489362 (-3150 3225);
PAINT SKYBLUE (-3150 3225);
DISPLAY INVISIBLE (-3150 3225);
FORCEPROP 1 LAST TOLERANCE 5%
J 2
(-2850 3225);
DISPLAY 0.489362 (-2850 3225);
PAINT SKYBLUE (-2850 3225);
DISPLAY INVISIBLE (-2850 3225);
FORCEPROP 1 LAST PART_NUMBER CS03302JB29
J 0
(-3075 3300);
DISPLAY 0.489362 (-3075 3300);
PAINT SKYBLUE (-3075 3300);
DISPLAY INVISIBLE (-3075 3300);
FORCEPROP 1 LAST PACK_TYPE 0402LF
J 0
(-3150 3175);
DISPLAY 0.489362 (-3150 3175);
PAINT SKYBLUE (-3150 3175);
DISPLAY INVISIBLE (-3150 3175);
FORCEPROP 2 LAST ROOM RST_CPU0_PLD_TO_DIMM
J 0
(-3000 3350);
DISPLAY 0.744681 (-3000 3350);
PAINT RED (-3000 3350);
DISPLAY INVISIBLE (-3000 3350);
FORCEADD Q_RES..1
R 2
(-2975 3000);
FORCEPROP 1 LAST LOCATION R1275
J 0
(-3175 3000);
DISPLAY 0.489362 (-3175 3000);
PAINT SKYBLUE (-3175 3000);
FORCEPROP 0 LAST $SEC 1
J 0
(-3025 3050);
DISPLAY 0.680851 (-3025 3050);
PAINT MONO (-3025 3050);
DISPLAY INVISIBLE (-3025 3050);
FORCEPROP 0 LAST CDS_SEC 1
J 0
(-3025 3050);
DISPLAY 1.021277 (-3025 3050);
DISPLAY INVISIBLE (-3025 3050);
FORCEPROP 1 LASTPIN (-2875 3000) $PN 1
J 2
(-2887 3012);
DISPLAY 0.489362 (-2887 3012);
PAINT MONO (-2887 3012);
FORCEPROP 1 LASTPIN (-3075 3000) $PN 2
J 2
(-3060 3010);
DISPLAY 0.489362 (-3060 3010);
PAINT MONO (-3060 3010);
FORCEPROP 1 LAST VALUE 33
J 0
(-2850 3000);
DISPLAY 0.489362 (-2850 3000);
PAINT SKYBLUE (-2850 3000);
FORCEPROP 2 LAST CDS_LIB pure_quanta
J 0
(-2975 3000);
DISPLAY INVISIBLE (-2975 3000);
FORCEPROP 2 LAST BOM_COST MEM
J 0
(-3000 3150);
DISPLAY 0.744681 (-3000 3150);
PAINT WHITE (-3000 3150);
DISPLAY INVISIBLE (-3000 3150);
FORCEPROP 1 LAST PATH I1282
J 2
(-2925 3150);
DISPLAY 0.978723 (-2925 3150);
PAINT WHITE (-2925 3150);
DISPLAY INVISIBLE (-2925 3150);
FORCEPROP 1 LAST WATTAGE 1/16W
J 0
(-2900 2925);
DISPLAY 0.489362 (-2900 2925);
PAINT SKYBLUE (-2900 2925);
DISPLAY INVISIBLE (-2900 2925);
FORCEPROP 1 LAST MATERIAL CHIP
J 0
(-3150 2975);
DISPLAY 0.489362 (-3150 2975);
PAINT SKYBLUE (-3150 2975);
DISPLAY INVISIBLE (-3150 2975);
FORCEPROP 1 LAST TOLERANCE 5%
J 2
(-2850 2975);
DISPLAY 0.489362 (-2850 2975);
PAINT SKYBLUE (-2850 2975);
DISPLAY INVISIBLE (-2850 2975);
FORCEPROP 1 LAST PART_NUMBER CS03302JB29
J 0
(-3075 3050);
DISPLAY 0.489362 (-3075 3050);
PAINT SKYBLUE (-3075 3050);
DISPLAY INVISIBLE (-3075 3050);
FORCEPROP 1 LAST PACK_TYPE 0402LF
J 0
(-3150 2925);
DISPLAY 0.489362 (-3150 2925);
PAINT SKYBLUE (-3150 2925);
DISPLAY INVISIBLE (-3150 2925);
FORCEPROP 2 LAST ROOM RST_CPU0_PLD_TO_DIMM
J 0
(-3000 3100);
DISPLAY 0.744681 (-3000 3100);
PAINT RED (-3000 3100);
DISPLAY INVISIBLE (-3000 3100);
FORCEADD OFFPAGE..2
(-3025 1450);
FORCEPROP 2 LAST $XR1 148 
J 0
(-2746 1450);
DISPLAY 0.638298 (-2746 1450);
PAINT MONO (-2746 1450);
FORCEPROP 2 LAST $XR0 84 
J 0
(-2836 1450);
DISPLAY 0.638298 (-2836 1450);
PAINT MONO (-2836 1450);
FORCEPROP 2 LAST CDS_LIB standard
J 0
(-3025 1450);
DISPLAY INVISIBLE (-3025 1450);
FORCEPROP 1 LAST OFFPAGE TRUE
J 0
(-2700 1325);
DISPLAY 0.872340 (-2700 1325);
PAINT GREEN (-2700 1325);
DISPLAY INVISIBLE (-2700 1325);
FORCEPROP 1 LAST COMMENT_BODY TRUE
J 0
(-3070 1355);
DISPLAY 0.872340 (-3070 1355);
PAINT GREEN (-3070 1355);
DISPLAY INVISIBLE (-3070 1355);
FORCEPROP 2 LAST PATH I1283
J 0
(-2725 1500);
DISPLAY 0.680851 (-2725 1500);
DISPLAY INVISIBLE (-2725 1500);
FORCEADD OFFPAGE..1
R 2
(-3025 1400);
FORCEPROP 2 LAST $XR1 148 
J 0
(-2749 1400);
DISPLAY 0.638298 (-2749 1400);
PAINT MONO (-2749 1400);
FORCEPROP 2 LAST $XR0 84 
J 0
(-2839 1400);
DISPLAY 0.638298 (-2839 1400);
PAINT MONO (-2839 1400);
FORCEPROP 2 LAST CDS_LIB standard
J 0
(-3025 1400);
DISPLAY INVISIBLE (-3025 1400);
FORCEPROP 1 LAST OFFPAGE TRUE
J 2
(-3350 1275);
DISPLAY 0.872340 (-3350 1275);
PAINT GREEN (-3350 1275);
DISPLAY INVISIBLE (-3350 1275);
FORCEPROP 1 LAST COMMENT_BODY TRUE
J 2
(-3150 1300);
DISPLAY 0.872340 (-3150 1300);
PAINT GREEN (-3150 1300);
DISPLAY INVISIBLE (-3150 1300);
FORCEPROP 2 LAST PATH I1284
J 0
(-2725 1450);
DISPLAY 0.680851 (-2725 1450);
DISPLAY INVISIBLE (-2725 1450);
FORCEADD OFFPAGE..1
R 2
(-3025 1350);
FORCEPROP 2 LAST $XR1 148 
J 0
(-2749 1350);
DISPLAY 0.638298 (-2749 1350);
PAINT MONO (-2749 1350);
FORCEPROP 2 LAST $XR0 84 
J 0
(-2839 1350);
DISPLAY 0.638298 (-2839 1350);
PAINT MONO (-2839 1350);
FORCEPROP 2 LAST CDS_LIB standard
J 0
(-3025 1350);
DISPLAY INVISIBLE (-3025 1350);
FORCEPROP 1 LAST OFFPAGE TRUE
J 2
(-3350 1225);
DISPLAY 0.872340 (-3350 1225);
PAINT GREEN (-3350 1225);
DISPLAY INVISIBLE (-3350 1225);
FORCEPROP 1 LAST COMMENT_BODY TRUE
J 2
(-3150 1250);
DISPLAY 0.872340 (-3150 1250);
PAINT GREEN (-3150 1250);
DISPLAY INVISIBLE (-3150 1250);
FORCEPROP 2 LAST PATH I1285
J 0
(-2725 1400);
DISPLAY 0.680851 (-2725 1400);
DISPLAY INVISIBLE (-2725 1400);
FORCEADD OFFPAGE..1
R 2
(-3025 1250);
FORCEPROP 2 LAST $XR0 82 
J 0
(-2839 1250);
DISPLAY 0.638298 (-2839 1250);
PAINT MONO (-2839 1250);
FORCEPROP 2 LAST CDS_LIB standard
J 0
(-3025 1250);
DISPLAY INVISIBLE (-3025 1250);
FORCEPROP 1 LAST OFFPAGE TRUE
J 2
(-3350 1125);
DISPLAY 0.872340 (-3350 1125);
PAINT GREEN (-3350 1125);
DISPLAY INVISIBLE (-3350 1125);
FORCEPROP 1 LAST COMMENT_BODY TRUE
J 2
(-3150 1150);
DISPLAY 0.872340 (-3150 1150);
PAINT GREEN (-3150 1150);
DISPLAY INVISIBLE (-3150 1150);
FORCEPROP 2 LAST PATH I1286
J 0
(-2825 1300);
DISPLAY 0.680851 (-2825 1300);
DISPLAY INVISIBLE (-2825 1300);
FORCEADD OFFPAGE..1
R 2
(-3025 1200);
FORCEPROP 2 LAST $XR0 82 
J 0
(-2839 1200);
DISPLAY 0.638298 (-2839 1200);
PAINT MONO (-2839 1200);
FORCEPROP 2 LAST CDS_LIB standard
J 0
(-3025 1200);
DISPLAY INVISIBLE (-3025 1200);
FORCEPROP 1 LAST OFFPAGE TRUE
J 2
(-3350 1075);
DISPLAY 0.872340 (-3350 1075);
PAINT GREEN (-3350 1075);
DISPLAY INVISIBLE (-3350 1075);
FORCEPROP 1 LAST COMMENT_BODY TRUE
J 2
(-3150 1100);
DISPLAY 0.872340 (-3150 1100);
PAINT GREEN (-3150 1100);
DISPLAY INVISIBLE (-3150 1100);
FORCEPROP 2 LAST PATH I1287
J 0
(-2825 1250);
DISPLAY 0.680851 (-2825 1250);
DISPLAY INVISIBLE (-2825 1250);
FORCEADD OFFPAGE..1
R 2
(-3025 1300);
FORCEPROP 2 LAST $XR1 148 
J 0
(-2749 1300);
DISPLAY 0.638298 (-2749 1300);
PAINT MONO (-2749 1300);
FORCEPROP 2 LAST $XR0 84 
J 0
(-2839 1300);
DISPLAY 0.638298 (-2839 1300);
PAINT MONO (-2839 1300);
FORCEPROP 2 LAST CDS_LIB standard
J 0
(-3025 1300);
DISPLAY INVISIBLE (-3025 1300);
FORCEPROP 1 LAST OFFPAGE TRUE
J 2
(-3350 1175);
DISPLAY 0.872340 (-3350 1175);
PAINT GREEN (-3350 1175);
DISPLAY INVISIBLE (-3350 1175);
FORCEPROP 1 LAST COMMENT_BODY TRUE
J 2
(-3150 1200);
DISPLAY 0.872340 (-3150 1200);
PAINT GREEN (-3150 1200);
DISPLAY INVISIBLE (-3150 1200);
FORCEPROP 2 LAST PATH I1288
J 0
(-2725 1350);
DISPLAY 0.680851 (-2725 1350);
DISPLAY INVISIBLE (-2725 1350);
FORCEADD LCMXO3D9400HC5BG484C..3
(-5025 3850);
FORCEPROP 1 LAST LOCATION U18
J 0
(-5930 5393);
DISPLAY 0.489362 (-5930 5393);
PAINT SKYBLUE (-5930 5393);
FORCEPROP 0 LAST $SEC 3
J 0
(-5925 5525);
DISPLAY 0.680851 (-5925 5525);
PAINT MONO (-5925 5525);
DISPLAY INVISIBLE (-5925 5525);
FORCEPROP 0 LAST CDS_SEC 3
J 0
(-5925 5525);
DISPLAY 0.680851 (-5925 5525);
DISPLAY INVISIBLE (-5925 5525);
FORCEPROP 0 LASTPIN (-6075 5000) $PN B1
J 2
(-6085 5010);
DISPLAY 0.489362 (-6085 5010);
PAINT MONO (-6085 5010);
FORCEPROP 0 LASTPIN (-6075 4950) $PN A2
J 2
(-6085 4960);
DISPLAY 0.489362 (-6085 4960);
PAINT MONO (-6085 4960);
FORCEPROP 0 LASTPIN (-6075 4900) $PN E6
J 2
(-6085 4910);
DISPLAY 0.489362 (-6085 4910);
PAINT MONO (-6085 4910);
FORCEPROP 0 LASTPIN (-6075 4850) $PN F7
J 2
(-6085 4860);
DISPLAY 0.489362 (-6085 4860);
PAINT MONO (-6085 4860);
FORCEPROP 0 LASTPIN (-6075 4800) $PN B2
J 2
(-6085 4810);
DISPLAY 0.489362 (-6085 4810);
PAINT MONO (-6085 4810);
FORCEPROP 0 LASTPIN (-6075 4750) $PN A3
J 2
(-6085 4760);
DISPLAY 0.489362 (-6085 4760);
PAINT MONO (-6085 4760);
FORCEPROP 0 LASTPIN (-6075 4700) $PN C3
J 2
(-6085 4710);
DISPLAY 0.489362 (-6085 4710);
PAINT MONO (-6085 4710);
FORCEPROP 0 LASTPIN (-6075 4650) $PN C4
J 2
(-6085 4660);
DISPLAY 0.489362 (-6085 4660);
PAINT MONO (-6085 4660);
FORCEPROP 0 LASTPIN (-6075 4600) $PN B3
J 2
(-6085 4610);
DISPLAY 0.489362 (-6085 4610);
PAINT MONO (-6085 4610);
FORCEPROP 0 LASTPIN (-6075 4550) $PN A4
J 2
(-6085 4560);
DISPLAY 0.489362 (-6085 4560);
PAINT MONO (-6085 4560);
FORCEPROP 0 LASTPIN (-6075 4500) $PN F8
J 2
(-6085 4510);
DISPLAY 0.489362 (-6085 4510);
PAINT MONO (-6085 4510);
FORCEPROP 0 LASTPIN (-6075 4450) $PN G8
J 2
(-6085 4460);
DISPLAY 0.489362 (-6085 4460);
PAINT MONO (-6085 4460);
FORCEPROP 0 LASTPIN (-6075 4400) $PN B4
J 2
(-6085 4410);
DISPLAY 0.489362 (-6085 4410);
PAINT MONO (-6085 4410);
FORCEPROP 0 LASTPIN (-6075 4350) $PN A5
J 2
(-6085 4360);
DISPLAY 0.489362 (-6085 4360);
PAINT MONO (-6085 4360);
FORCEPROP 0 LASTPIN (-6075 4300) $PN D5
J 2
(-6085 4310);
DISPLAY 0.489362 (-6085 4310);
PAINT MONO (-6085 4310);
FORCEPROP 0 LASTPIN (-6075 4250) $PN C5
J 2
(-6085 4260);
DISPLAY 0.489362 (-6085 4260);
PAINT MONO (-6085 4260);
FORCEPROP 0 LASTPIN (-6075 4200) $PN B5
J 2
(-6085 4210);
DISPLAY 0.489362 (-6085 4210);
PAINT MONO (-6085 4210);
FORCEPROP 0 LASTPIN (-6075 4150) $PN A6
J 2
(-6085 4160);
DISPLAY 0.489362 (-6085 4160);
PAINT MONO (-6085 4160);
FORCEPROP 0 LASTPIN (-6075 4100) $PN D6
J 2
(-6085 4110);
DISPLAY 0.489362 (-6085 4110);
PAINT MONO (-6085 4110);
FORCEPROP 0 LASTPIN (-6075 4050) $PN E7
J 2
(-6085 4060);
DISPLAY 0.489362 (-6085 4060);
PAINT MONO (-6085 4060);
FORCEPROP 0 LASTPIN (-6075 4000) $PN B6
J 2
(-6085 4010);
DISPLAY 0.489362 (-6085 4010);
PAINT MONO (-6085 4010);
FORCEPROP 0 LASTPIN (-6075 3950) $PN A7
J 2
(-6085 3960);
DISPLAY 0.489362 (-6085 3960);
PAINT MONO (-6085 3960);
FORCEPROP 0 LASTPIN (-6075 3900) $PN C6
J 2
(-6085 3910);
DISPLAY 0.489362 (-6085 3910);
PAINT MONO (-6085 3910);
FORCEPROP 0 LASTPIN (-6075 3850) $PN D7
J 2
(-6085 3860);
DISPLAY 0.489362 (-6085 3860);
PAINT MONO (-6085 3860);
FORCEPROP 0 LASTPIN (-6075 3800) $PN C8
J 2
(-6085 3810);
DISPLAY 0.489362 (-6085 3810);
PAINT MONO (-6085 3810);
FORCEPROP 0 LASTPIN (-6075 3750) $PN D8
J 2
(-6085 3760);
DISPLAY 0.489362 (-6085 3760);
PAINT MONO (-6085 3760);
FORCEPROP 0 LASTPIN (-6075 3700) $PN B8
J 2
(-6085 3710);
DISPLAY 0.489362 (-6085 3710);
PAINT MONO (-6085 3710);
FORCEPROP 0 LASTPIN (-6075 3650) $PN A8
J 2
(-6085 3660);
DISPLAY 0.489362 (-6085 3660);
PAINT MONO (-6085 3660);
FORCEPROP 0 LASTPIN (-6075 3600) $PN C9
J 2
(-6085 3610);
DISPLAY 0.489362 (-6085 3610);
PAINT MONO (-6085 3610);
FORCEPROP 0 LASTPIN (-6075 3550) $PN D9
J 2
(-6085 3560);
DISPLAY 0.489362 (-6085 3560);
PAINT MONO (-6085 3560);
FORCEPROP 0 LASTPIN (-6075 3400) $PN B9
J 2
(-6085 3410);
DISPLAY 0.489362 (-6085 3410);
PAINT MONO (-6085 3410);
FORCEPROP 0 LASTPIN (-6075 3350) $PN A9
J 2
(-6085 3360);
DISPLAY 0.489362 (-6085 3360);
PAINT MONO (-6085 3360);
FORCEPROP 0 LASTPIN (-6075 3300) $PN F9
J 2
(-6085 3310);
DISPLAY 0.489362 (-6085 3310);
PAINT MONO (-6085 3310);
FORCEPROP 0 LASTPIN (-6075 3250) $PN G9
J 2
(-6085 3260);
DISPLAY 0.489362 (-6085 3260);
PAINT MONO (-6085 3260);
FORCEPROP 0 LASTPIN (-6075 3200) $PN F10
J 2
(-6085 3210);
DISPLAY 0.489362 (-6085 3210);
PAINT MONO (-6085 3210);
FORCEPROP 0 LASTPIN (-6075 3150) $PN E10
J 2
(-6085 3160);
DISPLAY 0.489362 (-6085 3160);
PAINT MONO (-6085 3160);
FORCEPROP 0 LASTPIN (-6075 3100) $PN B10
J 2
(-6085 3110);
DISPLAY 0.489362 (-6085 3110);
PAINT MONO (-6085 3110);
FORCEPROP 0 LASTPIN (-6075 3050) $PN A10
J 2
(-6085 3060);
DISPLAY 0.489362 (-6085 3060);
PAINT MONO (-6085 3060);
FORCEPROP 0 LASTPIN (-6075 3000) $PN G11
J 2
(-6085 3010);
DISPLAY 0.489362 (-6085 3010);
PAINT MONO (-6085 3010);
FORCEPROP 0 LASTPIN (-6075 2950) $PN F11
J 2
(-6085 2960);
DISPLAY 0.489362 (-6085 2960);
PAINT MONO (-6085 2960);
FORCEPROP 0 LASTPIN (-6075 2850) $PN B11
J 2
(-6085 2860);
DISPLAY 0.489362 (-6085 2860);
PAINT MONO (-6085 2860);
FORCEPROP 0 LASTPIN (-6075 2800) $PN A11
J 2
(-6085 2810);
DISPLAY 0.489362 (-6085 2810);
PAINT MONO (-6085 2810);
FORCEPROP 0 LASTPIN (-6075 2750) $PN E11
J 2
(-6085 2760);
DISPLAY 0.489362 (-6085 2760);
PAINT MONO (-6085 2760);
FORCEPROP 0 LASTPIN (-6075 2700) $PN D11
J 2
(-6085 2710);
DISPLAY 0.489362 (-6085 2710);
PAINT MONO (-6085 2710);
FORCEPROP 0 LASTPIN (-3975 5050) $PN D12
J 0
(-3965 5060);
DISPLAY 0.489362 (-3965 5060);
PAINT MONO (-3965 5060);
FORCEPROP 0 LASTPIN (-3975 5000) $PN E12
J 0
(-3965 5010);
DISPLAY 0.489362 (-3965 5010);
PAINT MONO (-3965 5010);
FORCEPROP 0 LASTPIN (-3975 4950) $PN B12
J 0
(-3965 4960);
DISPLAY 0.489362 (-3965 4960);
PAINT MONO (-3965 4960);
FORCEPROP 0 LASTPIN (-3975 4900) $PN A12
J 0
(-3965 4910);
DISPLAY 0.489362 (-3965 4910);
PAINT MONO (-3965 4910);
FORCEPROP 0 LASTPIN (-3975 4850) $PN G12
J 0
(-3965 4860);
DISPLAY 0.489362 (-3965 4860);
PAINT MONO (-3965 4860);
FORCEPROP 0 LASTPIN (-3975 4800) $PN F12
J 0
(-3965 4810);
DISPLAY 0.489362 (-3965 4810);
PAINT MONO (-3965 4810);
FORCEPROP 0 LASTPIN (-3975 4750) $PN E13
J 0
(-3965 4760);
DISPLAY 0.489362 (-3965 4760);
PAINT MONO (-3965 4760);
FORCEPROP 0 LASTPIN (-3975 4700) $PN F13
J 0
(-3965 4710);
DISPLAY 0.489362 (-3965 4710);
PAINT MONO (-3965 4710);
FORCEPROP 0 LASTPIN (-3975 4650) $PN A13
J 0
(-3965 4660);
DISPLAY 0.489362 (-3965 4660);
PAINT MONO (-3965 4660);
FORCEPROP 0 LASTPIN (-3975 4600) $PN B13
J 0
(-3965 4610);
DISPLAY 0.489362 (-3965 4610);
PAINT MONO (-3965 4610);
FORCEPROP 0 LASTPIN (-3975 4550) $PN C13
J 0
(-3965 4560);
DISPLAY 0.489362 (-3965 4560);
PAINT MONO (-3965 4560);
FORCEPROP 0 LASTPIN (-3975 4500) $PN D13
J 0
(-3965 4510);
DISPLAY 0.489362 (-3965 4510);
PAINT MONO (-3965 4510);
FORCEPROP 0 LASTPIN (-3975 4450) $PN A14
J 0
(-3965 4460);
DISPLAY 0.489362 (-3965 4460);
PAINT MONO (-3965 4460);
FORCEPROP 0 LASTPIN (-3975 4400) $PN B14
J 0
(-3965 4410);
DISPLAY 0.489362 (-3965 4410);
PAINT MONO (-3965 4410);
FORCEPROP 0 LASTPIN (-3975 4350) $PN C14
J 0
(-3965 4360);
DISPLAY 0.489362 (-3965 4360);
PAINT MONO (-3965 4360);
FORCEPROP 0 LASTPIN (-3975 4300) $PN D14
J 0
(-3965 4310);
DISPLAY 0.489362 (-3965 4310);
PAINT MONO (-3965 4310);
FORCEPROP 0 LASTPIN (-3975 4250) $PN G14
J 0
(-3965 4260);
DISPLAY 0.489362 (-3965 4260);
PAINT MONO (-3965 4260);
FORCEPROP 0 LASTPIN (-3975 4200) $PN F14
J 0
(-3965 4210);
DISPLAY 0.489362 (-3965 4210);
PAINT MONO (-3965 4210);
FORCEPROP 0 LASTPIN (-3975 4100) $PN A15
J 0
(-3965 4110);
DISPLAY 0.489362 (-3965 4110);
PAINT MONO (-3965 4110);
FORCEPROP 0 LASTPIN (-3975 4050) $PN B15
J 0
(-3965 4060);
DISPLAY 0.489362 (-3965 4060);
PAINT MONO (-3965 4060);
FORCEPROP 0 LASTPIN (-3975 4000) $PN C15
J 0
(-3965 4010);
DISPLAY 0.489362 (-3965 4010);
PAINT MONO (-3965 4010);
FORCEPROP 0 LASTPIN (-3975 3950) $PN D15
J 0
(-3965 3960);
DISPLAY 0.489362 (-3965 3960);
PAINT MONO (-3965 3960);
FORCEPROP 0 LASTPIN (-3975 3900) $PN A16
J 0
(-3965 3910);
DISPLAY 0.489362 (-3965 3910);
PAINT MONO (-3965 3910);
FORCEPROP 0 LASTPIN (-3975 3850) $PN B17
J 0
(-3965 3860);
DISPLAY 0.489362 (-3965 3860);
PAINT MONO (-3965 3860);
FORCEPROP 0 LASTPIN (-3975 3800) $PN C17
J 0
(-3965 3810);
DISPLAY 0.489362 (-3965 3810);
PAINT MONO (-3965 3810);
FORCEPROP 0 LASTPIN (-3975 3750) $PN D16
J 0
(-3965 3760);
DISPLAY 0.489362 (-3965 3760);
PAINT MONO (-3965 3760);
FORCEPROP 0 LASTPIN (-3975 3700) $PN A17
J 0
(-3965 3710);
DISPLAY 0.489362 (-3965 3710);
PAINT MONO (-3965 3710);
FORCEPROP 0 LASTPIN (-3975 3650) $PN B18
J 0
(-3965 3660);
DISPLAY 0.489362 (-3965 3660);
PAINT MONO (-3965 3660);
FORCEPROP 0 LASTPIN (-3975 3600) $PN E16
J 0
(-3965 3610);
DISPLAY 0.489362 (-3965 3610);
PAINT MONO (-3965 3610);
FORCEPROP 0 LASTPIN (-3975 3550) $PN D17
J 0
(-3965 3560);
DISPLAY 0.489362 (-3965 3560);
PAINT MONO (-3965 3560);
FORCEPROP 0 LASTPIN (-3975 3500) $PN A18
J 0
(-3965 3510);
DISPLAY 0.489362 (-3965 3510);
PAINT MONO (-3965 3510);
FORCEPROP 0 LASTPIN (-3975 3450) $PN B19
J 0
(-3965 3460);
DISPLAY 0.489362 (-3965 3460);
PAINT MONO (-3965 3460);
FORCEPROP 0 LASTPIN (-3975 3400) $PN C18
J 0
(-3965 3410);
DISPLAY 0.489362 (-3965 3410);
PAINT MONO (-3965 3410);
FORCEPROP 0 LASTPIN (-3975 3350) $PN D18
J 0
(-3965 3360);
DISPLAY 0.489362 (-3965 3360);
PAINT MONO (-3965 3360);
FORCEPROP 0 LASTPIN (-3975 3250) $PN A19
J 0
(-3965 3260);
DISPLAY 0.489362 (-3965 3260);
PAINT MONO (-3965 3260);
FORCEPROP 0 LASTPIN (-3975 3200) $PN B20
J 0
(-3965 3210);
DISPLAY 0.489362 (-3965 3210);
PAINT MONO (-3965 3210);
FORCEPROP 0 LASTPIN (-3975 3150) $PN F15
J 0
(-3965 3160);
DISPLAY 0.489362 (-3965 3160);
PAINT MONO (-3965 3160);
FORCEPROP 0 LASTPIN (-3975 3100) $PN G15
J 0
(-3965 3110);
DISPLAY 0.489362 (-3965 3110);
PAINT MONO (-3965 3110);
FORCEPROP 0 LASTPIN (-3975 3000) $PN A20
J 0
(-3965 3010);
DISPLAY 0.489362 (-3965 3010);
PAINT MONO (-3965 3010);
FORCEPROP 0 LASTPIN (-3975 2950) $PN B21
J 0
(-3965 2960);
DISPLAY 0.489362 (-3965 2960);
PAINT MONO (-3965 2960);
FORCEPROP 0 LASTPIN (-3975 2900) $PN C19
J 0
(-3965 2910);
DISPLAY 0.489362 (-3965 2910);
PAINT MONO (-3965 2910);
FORCEPROP 0 LASTPIN (-3975 2850) $PN C20
J 0
(-3965 2860);
DISPLAY 0.489362 (-3965 2860);
PAINT MONO (-3965 2860);
FORCEPROP 0 LASTPIN (-3975 2750) $PN A21
J 0
(-3965 2760);
DISPLAY 0.489362 (-3965 2760);
PAINT MONO (-3965 2760);
FORCEPROP 0 LASTPIN (-3975 2700) $PN B22
J 0
(-3965 2710);
DISPLAY 0.489362 (-3965 2710);
PAINT MONO (-3965 2710);
FORCEPROP 2 LAST PART_TYPE SMLF
J 0
(-5925 5485);
DISPLAY 0.680851 (-5925 5485);
FORCEPROP 1 LAST MATERIAL IC
J 0
(-5930 5119);
DISPLAY 0.489362 (-5930 5119);
PAINT SKYBLUE (-5930 5119);
FORCEPROP 2 LAST VALUE LCMXO3D-9400HC-5BG484C
J 0
(-5925 5440);
DISPLAY 0.489362 (-5925 5440);
PAINT SKYBLUE (-5925 5440);
FORCEPROP 1 LAST PART_NUMBER AJ094000T05
J 0
(-5930 5246);
DISPLAY 0.489362 (-5930 5246);
PAINT SKYBLUE (-5930 5246);
FORCEPROP 2 LAST CDS_LIB pure_quanta
J 0
(-5025 3850);
DISPLAY INVISIBLE (-5025 3850);
FORCEPROP 1 LAST NEEDS_NO_SIZE TRUE
J 0
(-5025 3850);
DISPLAY 0.723404 (-5025 3850);
PAINT GREEN (-5025 3850);
DISPLAY INVISIBLE (-5025 3850);
FORCEPROP 1 LAST CDS_LMAN_SYM_OUTLINE -900,1250,900,-1250
J 0
(-5025 3850);
DISPLAY 0.468085 (-5025 3850);
PAINT GREEN (-5025 3850);
DISPLAY INVISIBLE (-5025 3850);
FORCEPROP 1 LAST PATH I1289
J 0
(-5025 3850);
DISPLAY 0.723404 (-5025 3850);
PAINT GREEN (-5025 3850);
DISPLAY INVISIBLE (-5025 3850);
FORCEADD LCMXO3D9400HC5BG484C..4
(-5575 1250);
FORCEPROP 1 LAST LOCATION U18
J 0
(-5972 1785);
DISPLAY 0.489362 (-5972 1785);
PAINT SKYBLUE (-5972 1785);
FORCEPROP 0 LAST $SEC 4
J 0
(-5950 1900);
DISPLAY 0.680851 (-5950 1900);
PAINT MONO (-5950 1900);
DISPLAY INVISIBLE (-5950 1900);
FORCEPROP 0 LAST CDS_SEC 4
J 0
(-5950 1900);
DISPLAY 0.680851 (-5950 1900);
DISPLAY INVISIBLE (-5950 1900);
FORCEPROP 0 LASTPIN (-5025 1450) $PN E8
J 0
(-5015 1460);
DISPLAY 0.489362 (-5015 1460);
PAINT MONO (-5015 1460);
FORCEPROP 0 LASTPIN (-5025 1400) $PN E9
J 0
(-5015 1410);
DISPLAY 0.489362 (-5015 1410);
PAINT MONO (-5015 1410);
FORCEPROP 0 LASTPIN (-5025 1350) $PN D10
J 0
(-5015 1360);
DISPLAY 0.489362 (-5015 1360);
PAINT MONO (-5015 1360);
FORCEPROP 0 LASTPIN (-5025 1300) $PN C10
J 0
(-5015 1310);
DISPLAY 0.489362 (-5015 1310);
PAINT MONO (-5015 1310);
FORCEPROP 0 LASTPIN (-5025 1250) $PN E14
J 0
(-5015 1260);
DISPLAY 0.489362 (-5015 1260);
PAINT MONO (-5015 1260);
FORCEPROP 0 LASTPIN (-5025 1200) $PN E15
J 0
(-5015 1210);
DISPLAY 0.489362 (-5015 1210);
PAINT MONO (-5015 1210);
FORCEPROP 0 LASTPIN (-5025 1150) $PN F16
J 0
(-5015 1160);
DISPLAY 0.489362 (-5015 1160);
PAINT MONO (-5015 1160);
FORCEPROP 0 LASTPIN (-5025 1100) $PN E17
J 0
(-5015 1110);
DISPLAY 0.489362 (-5015 1110);
PAINT MONO (-5015 1110);
FORCEPROP 1 LAST MATERIAL IC
J 0
(-5972 1511);
DISPLAY 0.489362 (-5972 1511);
PAINT SKYBLUE (-5972 1511);
FORCEPROP 2 LAST VALUE LCMXO3D-9400HC-5BG484C
J 0
(-5965 1820);
DISPLAY 0.489362 (-5965 1820);
PAINT SKYBLUE (-5965 1820);
FORCEPROP 1 LAST PART_NUMBER AJ094000T05
J 0
(-5972 1638);
DISPLAY 0.489362 (-5972 1638);
PAINT SKYBLUE (-5972 1638);
FORCEPROP 2 LAST PART_TYPE SMLF
J 0
(-5965 1865);
DISPLAY 0.680851 (-5965 1865);
FORCEPROP 2 LAST CDS_LIB pure_quanta
J 0
(-5575 1250);
DISPLAY INVISIBLE (-5575 1250);
FORCEPROP 1 LAST NEEDS_NO_SIZE TRUE
J 0
(-5575 1250);
DISPLAY 0.723404 (-5575 1250);
PAINT GREEN (-5575 1250);
DISPLAY INVISIBLE (-5575 1250);
FORCEPROP 1 LAST CDS_LMAN_SYM_OUTLINE -400,250,400,-250
J 0
(-5575 1250);
DISPLAY 0.468085 (-5575 1250);
PAINT GREEN (-5575 1250);
DISPLAY INVISIBLE (-5575 1250);
FORCEPROP 1 LAST PATH I1290
J 0
(-5575 1250);
DISPLAY 0.723404 (-5575 1250);
PAINT GREEN (-5575 1250);
DISPLAY INVISIBLE (-5575 1250);
FORCEADD Q_RES..1
R 2
(-7050 4950);
FORCEPROP 1 LAST LOCATION R170
J 0
(-7275 4950);
DISPLAY 0.489362 (-7275 4950);
PAINT SKYBLUE (-7275 4950);
FORCEPROP 0 LAST $SEC 1
J 0
(-7150 5000);
DISPLAY 0.680851 (-7150 5000);
PAINT MONO (-7150 5000);
DISPLAY INVISIBLE (-7150 5000);
FORCEPROP 0 LAST CDS_SEC 1
J 0
(-7150 5000);
DISPLAY 1.021277 (-7150 5000);
DISPLAY INVISIBLE (-7150 5000);
FORCEPROP 1 LASTPIN (-6950 4950) $PN 1
J 2
(-6962 4962);
DISPLAY 0.489362 (-6962 4962);
PAINT MONO (-6962 4962);
FORCEPROP 1 LASTPIN (-7150 4950) $PN 2
J 2
(-7112 4962);
DISPLAY 0.489362 (-7112 4962);
PAINT MONO (-7112 4962);
FORCEPROP 1 LAST VALUE 33
J 0
(-6925 4950);
DISPLAY 0.489362 (-6925 4950);
PAINT SKYBLUE (-6925 4950);
FORCEPROP 2 LAST CDS_LIB pure_quanta
J 0
(-7050 4950);
DISPLAY INVISIBLE (-7050 4950);
FORCEPROP 2 LAST BOM_COST MEM
J 0
(-7075 5100);
DISPLAY 0.744681 (-7075 5100);
PAINT WHITE (-7075 5100);
DISPLAY INVISIBLE (-7075 5100);
FORCEPROP 1 LAST PATH I1291
J 2
(-7000 5100);
DISPLAY 0.978723 (-7000 5100);
PAINT WHITE (-7000 5100);
DISPLAY INVISIBLE (-7000 5100);
FORCEPROP 1 LAST WATTAGE 1/16W
J 0
(-6975 4875);
DISPLAY 0.489362 (-6975 4875);
PAINT SKYBLUE (-6975 4875);
DISPLAY INVISIBLE (-6975 4875);
FORCEPROP 1 LAST MATERIAL CHIP
J 0
(-7225 4925);
DISPLAY 0.489362 (-7225 4925);
PAINT SKYBLUE (-7225 4925);
DISPLAY INVISIBLE (-7225 4925);
FORCEPROP 1 LAST TOLERANCE 5%
J 2
(-6925 4925);
DISPLAY 0.489362 (-6925 4925);
PAINT SKYBLUE (-6925 4925);
DISPLAY INVISIBLE (-6925 4925);
FORCEPROP 1 LAST PART_NUMBER CS03302JB29
J 0
(-7150 5000);
DISPLAY 0.489362 (-7150 5000);
PAINT SKYBLUE (-7150 5000);
DISPLAY INVISIBLE (-7150 5000);
FORCEPROP 1 LAST PACK_TYPE 0402LF
J 0
(-7225 4875);
DISPLAY 0.489362 (-7225 4875);
PAINT SKYBLUE (-7225 4875);
DISPLAY INVISIBLE (-7225 4875);
FORCEPROP 2 LAST ROOM RST_CPU0_PLD_TO_DIMM
J 0
(-7075 5050);
DISPLAY 0.744681 (-7075 5050);
PAINT RED (-7075 5050);
DISPLAY INVISIBLE (-7075 5050);
FORCEADD Q_RES..1
R 2
(-7050 5000);
FORCEPROP 1 LAST LOCATION R163
J 0
(-7275 5000);
DISPLAY 0.489362 (-7275 5000);
PAINT SKYBLUE (-7275 5000);
FORCEPROP 0 LAST $SEC 1
J 0
(-7175 5050);
DISPLAY 0.680851 (-7175 5050);
PAINT MONO (-7175 5050);
DISPLAY INVISIBLE (-7175 5050);
FORCEPROP 0 LAST CDS_SEC 1
J 0
(-7175 5050);
DISPLAY 1.021277 (-7175 5050);
DISPLAY INVISIBLE (-7175 5050);
FORCEPROP 1 LASTPIN (-6950 5000) $PN 1
J 2
(-6962 5012);
DISPLAY 0.489362 (-6962 5012);
PAINT MONO (-6962 5012);
FORCEPROP 1 LASTPIN (-7150 5000) $PN 2
J 2
(-7112 5012);
DISPLAY 0.489362 (-7112 5012);
PAINT MONO (-7112 5012);
FORCEPROP 1 LAST VALUE 33
J 0
(-6925 5000);
DISPLAY 0.489362 (-6925 5000);
PAINT SKYBLUE (-6925 5000);
FORCEPROP 2 LAST BOM_COST MEM
J 0
(-7075 5150);
DISPLAY 0.744681 (-7075 5150);
PAINT WHITE (-7075 5150);
DISPLAY INVISIBLE (-7075 5150);
FORCEPROP 2 LAST CDS_LIB pure_quanta
J 0
(-7050 5000);
DISPLAY INVISIBLE (-7050 5000);
FORCEPROP 1 LAST PATH I1292
J 2
(-7000 5150);
DISPLAY 0.978723 (-7000 5150);
PAINT WHITE (-7000 5150);
DISPLAY INVISIBLE (-7000 5150);
FORCEPROP 1 LAST WATTAGE 1/16W
J 0
(-6975 4925);
DISPLAY 0.489362 (-6975 4925);
PAINT SKYBLUE (-6975 4925);
DISPLAY INVISIBLE (-6975 4925);
FORCEPROP 1 LAST MATERIAL CHIP
J 0
(-7225 4975);
DISPLAY 0.489362 (-7225 4975);
PAINT SKYBLUE (-7225 4975);
DISPLAY INVISIBLE (-7225 4975);
FORCEPROP 1 LAST TOLERANCE 5%
J 2
(-6925 4975);
DISPLAY 0.489362 (-6925 4975);
PAINT SKYBLUE (-6925 4975);
DISPLAY INVISIBLE (-6925 4975);
FORCEPROP 1 LAST PART_NUMBER CS03302JB29
J 0
(-7150 5050);
DISPLAY 0.489362 (-7150 5050);
PAINT SKYBLUE (-7150 5050);
DISPLAY INVISIBLE (-7150 5050);
FORCEPROP 1 LAST PACK_TYPE 0402LF
J 0
(-7225 4925);
DISPLAY 0.489362 (-7225 4925);
PAINT SKYBLUE (-7225 4925);
DISPLAY INVISIBLE (-7225 4925);
FORCEPROP 2 LAST ROOM RST_CPU0_PLD_TO_DIMM
J 0
(-7075 5100);
DISPLAY 0.744681 (-7075 5100);
PAINT RED (-7075 5100);
DISPLAY INVISIBLE (-7075 5100);
FORCEADD Q_RES..1
R 2
(-7050 4850);
FORCEPROP 1 LAST LOCATION R166
J 0
(-7275 4850);
DISPLAY 0.489362 (-7275 4850);
PAINT SKYBLUE (-7275 4850);
FORCEPROP 0 LAST $SEC 1
J 0
(-7175 4900);
DISPLAY 0.680851 (-7175 4900);
PAINT MONO (-7175 4900);
DISPLAY INVISIBLE (-7175 4900);
FORCEPROP 0 LAST CDS_SEC 1
J 0
(-7175 4900);
DISPLAY 1.021277 (-7175 4900);
DISPLAY INVISIBLE (-7175 4900);
FORCEPROP 1 LASTPIN (-6950 4850) $PN 1
J 2
(-6962 4862);
DISPLAY 0.489362 (-6962 4862);
PAINT MONO (-6962 4862);
FORCEPROP 1 LASTPIN (-7150 4850) $PN 2
J 2
(-7112 4862);
DISPLAY 0.489362 (-7112 4862);
PAINT MONO (-7112 4862);
FORCEPROP 1 LAST VALUE 33
J 0
(-6925 4850);
DISPLAY 0.489362 (-6925 4850);
PAINT SKYBLUE (-6925 4850);
FORCEPROP 2 LAST BOM_COST MEM
J 0
(-7075 5000);
DISPLAY 0.744681 (-7075 5000);
PAINT WHITE (-7075 5000);
DISPLAY INVISIBLE (-7075 5000);
FORCEPROP 2 LAST CDS_LIB pure_quanta
J 0
(-7050 4850);
DISPLAY INVISIBLE (-7050 4850);
FORCEPROP 1 LAST PATH I1293
J 2
(-7000 5000);
DISPLAY 0.978723 (-7000 5000);
PAINT WHITE (-7000 5000);
DISPLAY INVISIBLE (-7000 5000);
FORCEPROP 1 LAST WATTAGE 1/16W
J 0
(-6975 4775);
DISPLAY 0.489362 (-6975 4775);
PAINT SKYBLUE (-6975 4775);
DISPLAY INVISIBLE (-6975 4775);
FORCEPROP 1 LAST MATERIAL CHIP
J 0
(-7225 4825);
DISPLAY 0.489362 (-7225 4825);
PAINT SKYBLUE (-7225 4825);
DISPLAY INVISIBLE (-7225 4825);
FORCEPROP 1 LAST TOLERANCE 5%
J 2
(-6925 4825);
DISPLAY 0.489362 (-6925 4825);
PAINT SKYBLUE (-6925 4825);
DISPLAY INVISIBLE (-6925 4825);
FORCEPROP 1 LAST PART_NUMBER CS03302JB29
J 0
(-7150 4900);
DISPLAY 0.489362 (-7150 4900);
PAINT SKYBLUE (-7150 4900);
DISPLAY INVISIBLE (-7150 4900);
FORCEPROP 1 LAST PACK_TYPE 0402LF
J 0
(-7225 4775);
DISPLAY 0.489362 (-7225 4775);
PAINT SKYBLUE (-7225 4775);
DISPLAY INVISIBLE (-7225 4775);
FORCEPROP 2 LAST ROOM RST_CPU0_PLD_TO_DIMM
J 0
(-7075 4950);
DISPLAY 0.744681 (-7075 4950);
PAINT RED (-7075 4950);
DISPLAY INVISIBLE (-7075 4950);
FORCEADD Q_RES..1
R 2
(-7050 4900);
FORCEPROP 1 LAST LOCATION R171
J 0
(-7275 4900);
DISPLAY 0.489362 (-7275 4900);
PAINT SKYBLUE (-7275 4900);
FORCEPROP 0 LAST $SEC 1
J 0
(-7150 4950);
DISPLAY 0.680851 (-7150 4950);
PAINT MONO (-7150 4950);
DISPLAY INVISIBLE (-7150 4950);
FORCEPROP 0 LAST CDS_SEC 1
J 0
(-7150 4950);
DISPLAY 1.021277 (-7150 4950);
DISPLAY INVISIBLE (-7150 4950);
FORCEPROP 1 LASTPIN (-6950 4900) $PN 1
J 2
(-6962 4912);
DISPLAY 0.489362 (-6962 4912);
PAINT MONO (-6962 4912);
FORCEPROP 1 LASTPIN (-7150 4900) $PN 2
J 2
(-7112 4912);
DISPLAY 0.489362 (-7112 4912);
PAINT MONO (-7112 4912);
FORCEPROP 1 LAST VALUE 33
J 0
(-6925 4900);
DISPLAY 0.489362 (-6925 4900);
PAINT SKYBLUE (-6925 4900);
FORCEPROP 2 LAST CDS_LIB pure_quanta
J 0
(-7050 4900);
DISPLAY INVISIBLE (-7050 4900);
FORCEPROP 2 LAST BOM_COST MEM
J 0
(-7075 5050);
DISPLAY 0.744681 (-7075 5050);
PAINT WHITE (-7075 5050);
DISPLAY INVISIBLE (-7075 5050);
FORCEPROP 1 LAST PATH I1294
J 2
(-7000 5050);
DISPLAY 0.978723 (-7000 5050);
PAINT WHITE (-7000 5050);
DISPLAY INVISIBLE (-7000 5050);
FORCEPROP 1 LAST WATTAGE 1/16W
J 0
(-6975 4825);
DISPLAY 0.489362 (-6975 4825);
PAINT SKYBLUE (-6975 4825);
DISPLAY INVISIBLE (-6975 4825);
FORCEPROP 1 LAST MATERIAL CHIP
J 0
(-7225 4875);
DISPLAY 0.489362 (-7225 4875);
PAINT SKYBLUE (-7225 4875);
DISPLAY INVISIBLE (-7225 4875);
FORCEPROP 1 LAST TOLERANCE 5%
J 2
(-6925 4875);
DISPLAY 0.489362 (-6925 4875);
PAINT SKYBLUE (-6925 4875);
DISPLAY INVISIBLE (-6925 4875);
FORCEPROP 1 LAST PART_NUMBER CS03302JB29
J 0
(-7150 4950);
DISPLAY 0.489362 (-7150 4950);
PAINT SKYBLUE (-7150 4950);
DISPLAY INVISIBLE (-7150 4950);
FORCEPROP 1 LAST PACK_TYPE 0402LF
J 0
(-7225 4825);
DISPLAY 0.489362 (-7225 4825);
PAINT SKYBLUE (-7225 4825);
DISPLAY INVISIBLE (-7225 4825);
FORCEPROP 2 LAST ROOM RST_CPU0_PLD_TO_DIMM
J 0
(-7075 5000);
DISPLAY 0.744681 (-7075 5000);
PAINT RED (-7075 5000);
DISPLAY INVISIBLE (-7075 5000);
FORCEADD Q_RES..1
R 2
(-7050 4800);
FORCEPROP 1 LAST LOCATION R169
J 0
(-7275 4800);
DISPLAY 0.489362 (-7275 4800);
PAINT SKYBLUE (-7275 4800);
FORCEPROP 0 LAST $SEC 1
J 0
(-7150 4850);
DISPLAY 0.680851 (-7150 4850);
PAINT MONO (-7150 4850);
DISPLAY INVISIBLE (-7150 4850);
FORCEPROP 0 LAST CDS_SEC 1
J 0
(-7150 4850);
DISPLAY 1.021277 (-7150 4850);
DISPLAY INVISIBLE (-7150 4850);
FORCEPROP 1 LASTPIN (-6950 4800) $PN 1
J 2
(-6962 4812);
DISPLAY 0.489362 (-6962 4812);
PAINT MONO (-6962 4812);
FORCEPROP 1 LASTPIN (-7150 4800) $PN 2
J 2
(-7112 4812);
DISPLAY 0.489362 (-7112 4812);
PAINT MONO (-7112 4812);
FORCEPROP 1 LAST VALUE 33
J 0
(-6925 4800);
DISPLAY 0.489362 (-6925 4800);
PAINT SKYBLUE (-6925 4800);
FORCEPROP 2 LAST CDS_LIB pure_quanta
J 0
(-7050 4800);
DISPLAY INVISIBLE (-7050 4800);
FORCEPROP 2 LAST BOM_COST MEM
J 0
(-7075 4950);
DISPLAY 0.744681 (-7075 4950);
PAINT WHITE (-7075 4950);
DISPLAY INVISIBLE (-7075 4950);
FORCEPROP 1 LAST PATH I1295
J 2
(-7000 4950);
DISPLAY 0.978723 (-7000 4950);
PAINT WHITE (-7000 4950);
DISPLAY INVISIBLE (-7000 4950);
FORCEPROP 1 LAST WATTAGE 1/16W
J 0
(-6975 4725);
DISPLAY 0.489362 (-6975 4725);
PAINT SKYBLUE (-6975 4725);
DISPLAY INVISIBLE (-6975 4725);
FORCEPROP 1 LAST MATERIAL CHIP
J 0
(-7225 4775);
DISPLAY 0.489362 (-7225 4775);
PAINT SKYBLUE (-7225 4775);
DISPLAY INVISIBLE (-7225 4775);
FORCEPROP 1 LAST TOLERANCE 5%
J 2
(-6925 4775);
DISPLAY 0.489362 (-6925 4775);
PAINT SKYBLUE (-6925 4775);
DISPLAY INVISIBLE (-6925 4775);
FORCEPROP 1 LAST PART_NUMBER CS03302JB29
J 0
(-7150 4850);
DISPLAY 0.489362 (-7150 4850);
PAINT SKYBLUE (-7150 4850);
DISPLAY INVISIBLE (-7150 4850);
FORCEPROP 1 LAST PACK_TYPE 0402LF
J 0
(-7225 4725);
DISPLAY 0.489362 (-7225 4725);
PAINT SKYBLUE (-7225 4725);
DISPLAY INVISIBLE (-7225 4725);
FORCEPROP 2 LAST ROOM RST_CPU0_PLD_TO_DIMM
J 0
(-7075 4900);
DISPLAY 0.744681 (-7075 4900);
PAINT RED (-7075 4900);
DISPLAY INVISIBLE (-7075 4900);
FORCEADD Q_RES..1
R 2
(-7050 4750);
FORCEPROP 1 LAST LOCATION R50
J 0
(-7275 4750);
DISPLAY 0.489362 (-7275 4750);
PAINT SKYBLUE (-7275 4750);
FORCEPROP 0 LAST $SEC 1
J 0
(-7100 4800);
DISPLAY 0.680851 (-7100 4800);
PAINT MONO (-7100 4800);
DISPLAY INVISIBLE (-7100 4800);
FORCEPROP 0 LAST CDS_SEC 1
J 0
(-7100 4800);
DISPLAY 1.021277 (-7100 4800);
DISPLAY INVISIBLE (-7100 4800);
FORCEPROP 1 LASTPIN (-6950 4750) $PN 1
J 2
(-6962 4762);
DISPLAY 0.489362 (-6962 4762);
PAINT MONO (-6962 4762);
FORCEPROP 1 LASTPIN (-7150 4750) $PN 2
J 2
(-7112 4762);
DISPLAY 0.489362 (-7112 4762);
PAINT MONO (-7112 4762);
FORCEPROP 1 LAST VALUE 33
J 0
(-6925 4750);
DISPLAY 0.489362 (-6925 4750);
PAINT SKYBLUE (-6925 4750);
FORCEPROP 2 LAST BOM_COST MEM
J 0
(-7075 4900);
DISPLAY 0.744681 (-7075 4900);
PAINT WHITE (-7075 4900);
DISPLAY INVISIBLE (-7075 4900);
FORCEPROP 2 LAST CDS_LIB pure_quanta
J 0
(-7050 4750);
DISPLAY INVISIBLE (-7050 4750);
FORCEPROP 1 LAST PATH I1296
J 2
(-7000 4900);
DISPLAY 0.978723 (-7000 4900);
PAINT WHITE (-7000 4900);
DISPLAY INVISIBLE (-7000 4900);
FORCEPROP 1 LAST WATTAGE 1/16W
J 0
(-6975 4675);
DISPLAY 0.489362 (-6975 4675);
PAINT SKYBLUE (-6975 4675);
DISPLAY INVISIBLE (-6975 4675);
FORCEPROP 1 LAST MATERIAL CHIP
J 0
(-7225 4725);
DISPLAY 0.489362 (-7225 4725);
PAINT SKYBLUE (-7225 4725);
DISPLAY INVISIBLE (-7225 4725);
FORCEPROP 1 LAST TOLERANCE 5%
J 2
(-6925 4725);
DISPLAY 0.489362 (-6925 4725);
PAINT SKYBLUE (-6925 4725);
DISPLAY INVISIBLE (-6925 4725);
FORCEPROP 1 LAST PART_NUMBER CS03302JB29
J 0
(-7150 4800);
DISPLAY 0.489362 (-7150 4800);
PAINT SKYBLUE (-7150 4800);
DISPLAY INVISIBLE (-7150 4800);
FORCEPROP 1 LAST PACK_TYPE 0402LF
J 0
(-7225 4675);
DISPLAY 0.489362 (-7225 4675);
PAINT SKYBLUE (-7225 4675);
DISPLAY INVISIBLE (-7225 4675);
FORCEPROP 2 LAST ROOM RST_CPU0_PLD_TO_DIMM
J 0
(-7075 4850);
DISPLAY 0.744681 (-7075 4850);
PAINT RED (-7075 4850);
DISPLAY INVISIBLE (-7075 4850);
FORCEADD Q_RES..1
R 2
(-7050 4700);
FORCEPROP 1 LAST LOCATION R164
J 0
(-7275 4700);
DISPLAY 0.489362 (-7275 4700);
PAINT SKYBLUE (-7275 4700);
FORCEPROP 0 LAST $SEC 1
J 0
(-7175 4750);
DISPLAY 0.680851 (-7175 4750);
PAINT MONO (-7175 4750);
DISPLAY INVISIBLE (-7175 4750);
FORCEPROP 0 LAST CDS_SEC 1
J 0
(-7175 4750);
DISPLAY 1.021277 (-7175 4750);
DISPLAY INVISIBLE (-7175 4750);
FORCEPROP 1 LASTPIN (-6950 4700) $PN 1
J 2
(-6962 4712);
DISPLAY 0.489362 (-6962 4712);
PAINT MONO (-6962 4712);
FORCEPROP 1 LASTPIN (-7150 4700) $PN 2
J 2
(-7112 4712);
DISPLAY 0.489362 (-7112 4712);
PAINT MONO (-7112 4712);
FORCEPROP 1 LAST VALUE 33
J 0
(-6925 4700);
DISPLAY 0.489362 (-6925 4700);
PAINT SKYBLUE (-6925 4700);
FORCEPROP 2 LAST CDS_LIB pure_quanta
J 0
(-7050 4700);
DISPLAY INVISIBLE (-7050 4700);
FORCEPROP 2 LAST BOM_COST MEM
J 0
(-7075 4850);
DISPLAY 0.744681 (-7075 4850);
PAINT WHITE (-7075 4850);
DISPLAY INVISIBLE (-7075 4850);
FORCEPROP 1 LAST PATH I1297
J 2
(-7000 4850);
DISPLAY 0.978723 (-7000 4850);
PAINT WHITE (-7000 4850);
DISPLAY INVISIBLE (-7000 4850);
FORCEPROP 1 LAST WATTAGE 1/16W
J 0
(-6975 4625);
DISPLAY 0.489362 (-6975 4625);
PAINT SKYBLUE (-6975 4625);
DISPLAY INVISIBLE (-6975 4625);
FORCEPROP 1 LAST MATERIAL CHIP
J 0
(-7225 4675);
DISPLAY 0.489362 (-7225 4675);
PAINT SKYBLUE (-7225 4675);
DISPLAY INVISIBLE (-7225 4675);
FORCEPROP 1 LAST TOLERANCE 5%
J 2
(-6925 4675);
DISPLAY 0.489362 (-6925 4675);
PAINT SKYBLUE (-6925 4675);
DISPLAY INVISIBLE (-6925 4675);
FORCEPROP 1 LAST PART_NUMBER CS03302JB29
J 0
(-7150 4750);
DISPLAY 0.489362 (-7150 4750);
PAINT SKYBLUE (-7150 4750);
DISPLAY INVISIBLE (-7150 4750);
FORCEPROP 1 LAST PACK_TYPE 0402LF
J 0
(-7225 4625);
DISPLAY 0.489362 (-7225 4625);
PAINT SKYBLUE (-7225 4625);
DISPLAY INVISIBLE (-7225 4625);
FORCEPROP 2 LAST ROOM RST_CPU0_PLD_TO_DIMM
J 0
(-7075 4800);
DISPLAY 0.744681 (-7075 4800);
PAINT RED (-7075 4800);
DISPLAY INVISIBLE (-7075 4800);
FORCEADD Q_RES..1
R 2
(-7050 4650);
FORCEPROP 1 LAST LOCATION R165
J 0
(-7275 4650);
DISPLAY 0.489362 (-7275 4650);
PAINT SKYBLUE (-7275 4650);
FORCEPROP 0 LAST $SEC 1
J 0
(-7175 4700);
DISPLAY 0.680851 (-7175 4700);
PAINT MONO (-7175 4700);
DISPLAY INVISIBLE (-7175 4700);
FORCEPROP 0 LAST CDS_SEC 1
J 0
(-7175 4700);
DISPLAY 1.021277 (-7175 4700);
DISPLAY INVISIBLE (-7175 4700);
FORCEPROP 1 LASTPIN (-6950 4650) $PN 1
J 2
(-6962 4662);
DISPLAY 0.489362 (-6962 4662);
PAINT MONO (-6962 4662);
FORCEPROP 1 LASTPIN (-7150 4650) $PN 2
J 2
(-7112 4662);
DISPLAY 0.489362 (-7112 4662);
PAINT MONO (-7112 4662);
FORCEPROP 1 LAST VALUE 33
J 0
(-6925 4650);
DISPLAY 0.489362 (-6925 4650);
PAINT SKYBLUE (-6925 4650);
FORCEPROP 2 LAST BOM_COST MEM
J 0
(-7075 4800);
DISPLAY 0.744681 (-7075 4800);
PAINT WHITE (-7075 4800);
DISPLAY INVISIBLE (-7075 4800);
FORCEPROP 2 LAST CDS_LIB pure_quanta
J 0
(-7050 4650);
DISPLAY INVISIBLE (-7050 4650);
FORCEPROP 1 LAST PATH I1298
J 2
(-7000 4800);
DISPLAY 0.978723 (-7000 4800);
PAINT WHITE (-7000 4800);
DISPLAY INVISIBLE (-7000 4800);
FORCEPROP 1 LAST WATTAGE 1/16W
J 0
(-6975 4575);
DISPLAY 0.489362 (-6975 4575);
PAINT SKYBLUE (-6975 4575);
DISPLAY INVISIBLE (-6975 4575);
FORCEPROP 1 LAST MATERIAL CHIP
J 0
(-7225 4625);
DISPLAY 0.489362 (-7225 4625);
PAINT SKYBLUE (-7225 4625);
DISPLAY INVISIBLE (-7225 4625);
FORCEPROP 1 LAST TOLERANCE 5%
J 2
(-6925 4625);
DISPLAY 0.489362 (-6925 4625);
PAINT SKYBLUE (-6925 4625);
DISPLAY INVISIBLE (-6925 4625);
FORCEPROP 1 LAST PART_NUMBER CS03302JB29
J 0
(-7150 4700);
DISPLAY 0.489362 (-7150 4700);
PAINT SKYBLUE (-7150 4700);
DISPLAY INVISIBLE (-7150 4700);
FORCEPROP 1 LAST PACK_TYPE 0402LF
J 0
(-7225 4575);
DISPLAY 0.489362 (-7225 4575);
PAINT SKYBLUE (-7225 4575);
DISPLAY INVISIBLE (-7225 4575);
FORCEPROP 2 LAST ROOM RST_CPU0_PLD_TO_DIMM
J 0
(-7075 4750);
DISPLAY 0.744681 (-7075 4750);
PAINT RED (-7075 4750);
DISPLAY INVISIBLE (-7075 4750);
FORCEADD Q_RES..1
R 2
(-7050 4550);
FORCEPROP 1 LAST LOCATION R167
J 0
(-7275 4550);
DISPLAY 0.489362 (-7275 4550);
PAINT SKYBLUE (-7275 4550);
FORCEPROP 0 LAST $SEC 1
J 0
(-7150 4600);
DISPLAY 0.680851 (-7150 4600);
PAINT MONO (-7150 4600);
DISPLAY INVISIBLE (-7150 4600);
FORCEPROP 0 LAST CDS_SEC 1
J 0
(-7150 4600);
DISPLAY 1.021277 (-7150 4600);
DISPLAY INVISIBLE (-7150 4600);
FORCEPROP 1 LASTPIN (-6950 4550) $PN 1
J 2
(-6962 4562);
DISPLAY 0.489362 (-6962 4562);
PAINT MONO (-6962 4562);
FORCEPROP 1 LASTPIN (-7150 4550) $PN 2
J 2
(-7112 4562);
DISPLAY 0.489362 (-7112 4562);
PAINT MONO (-7112 4562);
FORCEPROP 1 LAST VALUE 0
J 0
(-6925 4550);
DISPLAY 0.489362 (-6925 4550);
PAINT SKYBLUE (-6925 4550);
FORCEPROP 2 LAST BOM_COST MEM
J 0
(-7075 4700);
DISPLAY 0.744681 (-7075 4700);
PAINT WHITE (-7075 4700);
DISPLAY INVISIBLE (-7075 4700);
FORCEPROP 2 LAST CDS_LIB pure_quanta
J 0
(-7050 4550);
DISPLAY INVISIBLE (-7050 4550);
FORCEPROP 1 LAST PATH I1299
J 2
(-7000 4700);
DISPLAY 0.978723 (-7000 4700);
PAINT WHITE (-7000 4700);
DISPLAY INVISIBLE (-7000 4700);
FORCEPROP 1 LAST WATTAGE 1/16W
J 0
(-6975 4475);
DISPLAY 0.489362 (-6975 4475);
PAINT SKYBLUE (-6975 4475);
DISPLAY INVISIBLE (-6975 4475);
FORCEPROP 1 LAST MATERIAL CHIP
J 0
(-7225 4525);
DISPLAY 0.489362 (-7225 4525);
PAINT SKYBLUE (-7225 4525);
DISPLAY INVISIBLE (-7225 4525);
FORCEPROP 1 LAST TOLERANCE 5%
J 2
(-6925 4525);
DISPLAY 0.489362 (-6925 4525);
PAINT SKYBLUE (-6925 4525);
DISPLAY INVISIBLE (-6925 4525);
FORCEPROP 1 LAST PART_NUMBER CS00002JB38
J 0
(-7150 4600);
DISPLAY 0.489362 (-7150 4600);
PAINT SKYBLUE (-7150 4600);
DISPLAY INVISIBLE (-7150 4600);
FORCEPROP 1 LAST PACK_TYPE 0402LF
J 0
(-7225 4475);
DISPLAY 0.489362 (-7225 4475);
PAINT SKYBLUE (-7225 4475);
DISPLAY INVISIBLE (-7225 4475);
FORCEPROP 2 LAST ROOM RST_CPU0_PLD_TO_DIMM
J 0
(-7075 4650);
DISPLAY 0.744681 (-7075 4650);
PAINT RED (-7075 4650);
DISPLAY INVISIBLE (-7075 4650);
FORCEADD Q_RES..1
R 2
(-7050 4600);
FORCEPROP 1 LAST LOCATION R49
J 0
(-7275 4600);
DISPLAY 0.489362 (-7275 4600);
PAINT SKYBLUE (-7275 4600);
FORCEPROP 0 LAST $SEC 1
J 0
(-7100 4650);
DISPLAY 0.680851 (-7100 4650);
PAINT MONO (-7100 4650);
DISPLAY INVISIBLE (-7100 4650);
FORCEPROP 0 LAST CDS_SEC 1
J 0
(-7100 4650);
DISPLAY 1.021277 (-7100 4650);
DISPLAY INVISIBLE (-7100 4650);
FORCEPROP 1 LASTPIN (-6950 4600) $PN 1
J 2
(-6962 4612);
DISPLAY 0.489362 (-6962 4612);
PAINT MONO (-6962 4612);
FORCEPROP 1 LASTPIN (-7150 4600) $PN 2
J 2
(-7112 4612);
DISPLAY 0.489362 (-7112 4612);
PAINT MONO (-7112 4612);
FORCEPROP 1 LAST VALUE 33
J 0
(-6925 4600);
DISPLAY 0.489362 (-6925 4600);
PAINT SKYBLUE (-6925 4600);
FORCEPROP 2 LAST ROOM RST_CPU0_PLD_TO_DIMM
J 0
(-7075 4700);
DISPLAY 0.744681 (-7075 4700);
PAINT RED (-7075 4700);
DISPLAY INVISIBLE (-7075 4700);
FORCEPROP 1 LAST PACK_TYPE 0402LF
J 0
(-7225 4525);
DISPLAY 0.489362 (-7225 4525);
PAINT SKYBLUE (-7225 4525);
DISPLAY INVISIBLE (-7225 4525);
FORCEPROP 1 LAST PART_NUMBER CS03302JB29
J 0
(-7150 4650);
DISPLAY 0.489362 (-7150 4650);
PAINT SKYBLUE (-7150 4650);
DISPLAY INVISIBLE (-7150 4650);
FORCEPROP 1 LAST TOLERANCE 5%
J 2
(-6925 4575);
DISPLAY 0.489362 (-6925 4575);
PAINT SKYBLUE (-6925 4575);
DISPLAY INVISIBLE (-6925 4575);
FORCEPROP 1 LAST MATERIAL CHIP
J 0
(-7225 4575);
DISPLAY 0.489362 (-7225 4575);
PAINT SKYBLUE (-7225 4575);
DISPLAY INVISIBLE (-7225 4575);
FORCEPROP 1 LAST WATTAGE 1/16W
J 0
(-6975 4525);
DISPLAY 0.489362 (-6975 4525);
PAINT SKYBLUE (-6975 4525);
DISPLAY INVISIBLE (-6975 4525);
FORCEPROP 2 LAST BOM_COST MEM
J 0
(-7075 4750);
DISPLAY 0.744681 (-7075 4750);
PAINT WHITE (-7075 4750);
DISPLAY INVISIBLE (-7075 4750);
FORCEPROP 1 LAST PATH I1300
J 2
(-7000 4750);
DISPLAY 0.978723 (-7000 4750);
PAINT WHITE (-7000 4750);
DISPLAY INVISIBLE (-7000 4750);
FORCEPROP 2 LAST CDS_LIB pure_quanta
J 0
(-7050 4600);
DISPLAY INVISIBLE (-7050 4600);
FORCEADD Q_RES..1
R 2
(-7050 4450);
FORCEPROP 1 LAST LOCATION R58
J 0
(-7275 4450);
DISPLAY 0.489362 (-7275 4450);
PAINT SKYBLUE (-7275 4450);
FORCEPROP 0 LAST $SEC 1
J 0
(-6925 4475);
DISPLAY 0.680851 (-6925 4475);
PAINT MONO (-6925 4475);
DISPLAY INVISIBLE (-6925 4475);
FORCEPROP 0 LAST CDS_SEC 1
J 0
(-6925 4475);
DISPLAY 0.680851 (-6925 4475);
DISPLAY INVISIBLE (-6925 4475);
FORCEPROP 1 LASTPIN (-6950 4450) $PN 1
J 2
(-6962 4462);
DISPLAY 0.489362 (-6962 4462);
PAINT MONO (-6962 4462);
FORCEPROP 1 LASTPIN (-7150 4450) $PN 2
J 2
(-7112 4462);
DISPLAY 0.489362 (-7112 4462);
PAINT MONO (-7112 4462);
FORCEPROP 1 LAST VALUE 33
J 0
(-6925 4450);
DISPLAY 0.489362 (-6925 4450);
PAINT SKYBLUE (-6925 4450);
FORCEPROP 2 LAST BOM_COST MEM
J 0
(-7075 4600);
DISPLAY 0.744681 (-7075 4600);
PAINT WHITE (-7075 4600);
DISPLAY INVISIBLE (-7075 4600);
FORCEPROP 2 LAST CDS_LIB pure_quanta
J 0
(-7050 4450);
DISPLAY INVISIBLE (-7050 4450);
FORCEPROP 1 LAST PATH I1301
J 2
(-7000 4600);
DISPLAY 0.978723 (-7000 4600);
PAINT WHITE (-7000 4600);
DISPLAY INVISIBLE (-7000 4600);
FORCEPROP 1 LAST WATTAGE 1/16W
J 0
(-6975 4375);
DISPLAY 0.489362 (-6975 4375);
PAINT SKYBLUE (-6975 4375);
DISPLAY INVISIBLE (-6975 4375);
FORCEPROP 1 LAST MATERIAL CHIP
J 0
(-7225 4425);
DISPLAY 0.489362 (-7225 4425);
PAINT SKYBLUE (-7225 4425);
DISPLAY INVISIBLE (-7225 4425);
FORCEPROP 1 LAST TOLERANCE 5%
J 2
(-6925 4425);
DISPLAY 0.489362 (-6925 4425);
PAINT SKYBLUE (-6925 4425);
DISPLAY INVISIBLE (-6925 4425);
FORCEPROP 1 LAST PART_NUMBER CS03302JB29
J 0
(-7150 4500);
DISPLAY 0.489362 (-7150 4500);
PAINT SKYBLUE (-7150 4500);
DISPLAY INVISIBLE (-7150 4500);
FORCEPROP 1 LAST PACK_TYPE 0402LF
J 0
(-7225 4375);
DISPLAY 0.489362 (-7225 4375);
PAINT SKYBLUE (-7225 4375);
DISPLAY INVISIBLE (-7225 4375);
FORCEPROP 2 LAST ROOM RST_CPU0_PLD_TO_DIMM
J 0
(-7075 4550);
DISPLAY 0.744681 (-7075 4550);
PAINT RED (-7075 4550);
DISPLAY INVISIBLE (-7075 4550);
FORCEADD Q_RES..1
R 2
(-7050 4300);
FORCEPROP 1 LAST LOCATION R172
J 0
(-7275 4300);
DISPLAY 0.489362 (-7275 4300);
PAINT SKYBLUE (-7275 4300);
FORCEPROP 0 LAST $SEC 1
J 0
(-7150 4350);
DISPLAY 0.680851 (-7150 4350);
PAINT MONO (-7150 4350);
DISPLAY INVISIBLE (-7150 4350);
FORCEPROP 0 LAST CDS_SEC 1
J 0
(-7150 4350);
DISPLAY 1.021277 (-7150 4350);
DISPLAY INVISIBLE (-7150 4350);
FORCEPROP 1 LASTPIN (-6950 4300) $PN 1
J 2
(-6962 4312);
DISPLAY 0.489362 (-6962 4312);
PAINT MONO (-6962 4312);
FORCEPROP 1 LASTPIN (-7150 4300) $PN 2
J 2
(-7112 4312);
DISPLAY 0.489362 (-7112 4312);
PAINT MONO (-7112 4312);
FORCEPROP 1 LAST VALUE 33
J 0
(-6925 4300);
DISPLAY 0.489362 (-6925 4300);
PAINT SKYBLUE (-6925 4300);
FORCEPROP 2 LAST ROOM RST_CPU0_PLD_TO_DIMM
J 0
(-7075 4400);
DISPLAY 0.744681 (-7075 4400);
PAINT RED (-7075 4400);
DISPLAY INVISIBLE (-7075 4400);
FORCEPROP 1 LAST PACK_TYPE 0402LF
J 0
(-7225 4225);
DISPLAY 0.489362 (-7225 4225);
PAINT SKYBLUE (-7225 4225);
DISPLAY INVISIBLE (-7225 4225);
FORCEPROP 1 LAST PART_NUMBER CS03302JB29
J 0
(-7150 4350);
DISPLAY 0.489362 (-7150 4350);
PAINT SKYBLUE (-7150 4350);
DISPLAY INVISIBLE (-7150 4350);
FORCEPROP 1 LAST TOLERANCE 5%
J 2
(-6925 4275);
DISPLAY 0.489362 (-6925 4275);
PAINT SKYBLUE (-6925 4275);
DISPLAY INVISIBLE (-6925 4275);
FORCEPROP 1 LAST MATERIAL CHIP
J 0
(-7225 4275);
DISPLAY 0.489362 (-7225 4275);
PAINT SKYBLUE (-7225 4275);
DISPLAY INVISIBLE (-7225 4275);
FORCEPROP 1 LAST WATTAGE 1/16W
J 0
(-6975 4225);
DISPLAY 0.489362 (-6975 4225);
PAINT SKYBLUE (-6975 4225);
DISPLAY INVISIBLE (-6975 4225);
FORCEPROP 2 LAST BOM_COST MEM
J 0
(-7075 4450);
DISPLAY 0.744681 (-7075 4450);
PAINT WHITE (-7075 4450);
DISPLAY INVISIBLE (-7075 4450);
FORCEPROP 1 LAST PATH I1302
J 2
(-7000 4450);
DISPLAY 0.978723 (-7000 4450);
PAINT WHITE (-7000 4450);
DISPLAY INVISIBLE (-7000 4450);
FORCEPROP 2 LAST CDS_LIB pure_quanta
J 0
(-7050 4300);
DISPLAY INVISIBLE (-7050 4300);
FORCEADD Q_RES..1
R 2
(-7050 4000);
FORCEPROP 1 LAST LOCATION R1310
J 0
(-7275 4000);
DISPLAY 0.489362 (-7275 4000);
PAINT SKYBLUE (-7275 4000);
FORCEPROP 0 LAST $SEC 1
J 0
(-7150 4050);
DISPLAY 0.680851 (-7150 4050);
PAINT MONO (-7150 4050);
DISPLAY INVISIBLE (-7150 4050);
FORCEPROP 0 LAST CDS_SEC 1
J 0
(-7150 4050);
DISPLAY 0.680851 (-7150 4050);
DISPLAY INVISIBLE (-7150 4050);
FORCEPROP 1 LASTPIN (-6950 4000) $PN 1
J 2
(-6962 4012);
DISPLAY 0.489362 (-6962 4012);
PAINT MONO (-6962 4012);
FORCEPROP 1 LASTPIN (-7150 4000) $PN 2
J 2
(-7112 4012);
DISPLAY 0.489362 (-7112 4012);
PAINT MONO (-7112 4012);
FORCEPROP 1 LAST VALUE 33
J 0
(-6925 4000);
DISPLAY 0.489362 (-6925 4000);
PAINT SKYBLUE (-6925 4000);
FORCEPROP 2 LAST CDS_LIB pure_quanta
J 0
(-7050 4000);
DISPLAY INVISIBLE (-7050 4000);
FORCEPROP 1 LAST PATH I1303
J 2
(-7000 4150);
DISPLAY 0.978723 (-7000 4150);
PAINT WHITE (-7000 4150);
DISPLAY INVISIBLE (-7000 4150);
FORCEPROP 2 LAST ROOM RST_CPU0_PLD_TO_DIMM
J 0
(-7075 4100);
DISPLAY 0.744681 (-7075 4100);
PAINT RED (-7075 4100);
DISPLAY INVISIBLE (-7075 4100);
FORCEPROP 1 LAST PACK_TYPE 0402LF
J 0
(-7225 3925);
DISPLAY 0.489362 (-7225 3925);
PAINT SKYBLUE (-7225 3925);
DISPLAY INVISIBLE (-7225 3925);
FORCEPROP 1 LAST PART_NUMBER CS03302JB29
J 0
(-7150 4050);
DISPLAY 0.489362 (-7150 4050);
PAINT SKYBLUE (-7150 4050);
DISPLAY INVISIBLE (-7150 4050);
FORCEPROP 1 LAST TOLERANCE 5%
J 2
(-6925 3975);
DISPLAY 0.489362 (-6925 3975);
PAINT SKYBLUE (-6925 3975);
DISPLAY INVISIBLE (-6925 3975);
FORCEPROP 1 LAST MATERIAL CHIP
J 0
(-7225 3975);
DISPLAY 0.489362 (-7225 3975);
PAINT SKYBLUE (-7225 3975);
DISPLAY INVISIBLE (-7225 3975);
FORCEPROP 1 LAST WATTAGE 1/16W
J 0
(-6975 3925);
DISPLAY 0.489362 (-6975 3925);
PAINT SKYBLUE (-6975 3925);
DISPLAY INVISIBLE (-6975 3925);
FORCEPROP 2 LAST BOM_COST MEM
J 0
(-7075 4150);
DISPLAY 0.744681 (-7075 4150);
PAINT WHITE (-7075 4150);
DISPLAY INVISIBLE (-7075 4150);
FORCEADD Q_RES..1
R 2
(-7050 3900);
FORCEPROP 1 LAST LOCATION R168
J 0
(-7275 3900);
DISPLAY 0.489362 (-7275 3900);
PAINT SKYBLUE (-7275 3900);
FORCEPROP 0 LAST $SEC 1
J 0
(-7150 3950);
DISPLAY 0.680851 (-7150 3950);
PAINT MONO (-7150 3950);
DISPLAY INVISIBLE (-7150 3950);
FORCEPROP 0 LAST CDS_SEC 1
J 0
(-7150 3950);
DISPLAY 1.021277 (-7150 3950);
DISPLAY INVISIBLE (-7150 3950);
FORCEPROP 1 LASTPIN (-6950 3900) $PN 1
J 2
(-6962 3912);
DISPLAY 0.489362 (-6962 3912);
PAINT MONO (-6962 3912);
FORCEPROP 1 LASTPIN (-7150 3900) $PN 2
J 2
(-7112 3912);
DISPLAY 0.489362 (-7112 3912);
PAINT MONO (-7112 3912);
FORCEPROP 1 LAST VALUE 0
J 0
(-6925 3900);
DISPLAY 0.489362 (-6925 3900);
PAINT SKYBLUE (-6925 3900);
FORCEPROP 2 LAST BOM_COST MEM
J 0
(-7075 4050);
DISPLAY 0.744681 (-7075 4050);
PAINT WHITE (-7075 4050);
DISPLAY INVISIBLE (-7075 4050);
FORCEPROP 2 LAST CDS_LIB pure_quanta
J 0
(-7050 3900);
DISPLAY INVISIBLE (-7050 3900);
FORCEPROP 1 LAST PATH I1304
J 2
(-7000 4050);
DISPLAY 0.978723 (-7000 4050);
PAINT WHITE (-7000 4050);
DISPLAY INVISIBLE (-7000 4050);
FORCEPROP 1 LAST WATTAGE 1/16W
J 0
(-6975 3825);
DISPLAY 0.489362 (-6975 3825);
PAINT SKYBLUE (-6975 3825);
DISPLAY INVISIBLE (-6975 3825);
FORCEPROP 1 LAST MATERIAL CHIP
J 0
(-7225 3875);
DISPLAY 0.489362 (-7225 3875);
PAINT SKYBLUE (-7225 3875);
DISPLAY INVISIBLE (-7225 3875);
FORCEPROP 1 LAST TOLERANCE 5%
J 2
(-6925 3875);
DISPLAY 0.489362 (-6925 3875);
PAINT SKYBLUE (-6925 3875);
DISPLAY INVISIBLE (-6925 3875);
FORCEPROP 1 LAST PART_NUMBER CS00002JB38
J 0
(-7150 3950);
DISPLAY 0.489362 (-7150 3950);
PAINT SKYBLUE (-7150 3950);
DISPLAY INVISIBLE (-7150 3950);
FORCEPROP 1 LAST PACK_TYPE 0402LF
J 0
(-7225 3825);
DISPLAY 0.489362 (-7225 3825);
PAINT SKYBLUE (-7225 3825);
DISPLAY INVISIBLE (-7225 3825);
FORCEPROP 2 LAST ROOM RST_CPU0_PLD_TO_DIMM
J 0
(-7075 4000);
DISPLAY 0.744681 (-7075 4000);
PAINT RED (-7075 4000);
DISPLAY INVISIBLE (-7075 4000);
FORCEADD Q_RES..1
R 2
(-7050 3700);
FORCEPROP 1 LAST LOCATION R1312
J 0
(-7275 3700);
DISPLAY 0.489362 (-7275 3700);
PAINT SKYBLUE (-7275 3700);
FORCEPROP 0 LAST $SEC 1
J 0
(-7150 3750);
DISPLAY 0.680851 (-7150 3750);
PAINT MONO (-7150 3750);
DISPLAY INVISIBLE (-7150 3750);
FORCEPROP 0 LAST CDS_SEC 1
J 0
(-7150 3750);
DISPLAY 0.680851 (-7150 3750);
DISPLAY INVISIBLE (-7150 3750);
FORCEPROP 1 LASTPIN (-6950 3700) $PN 1
J 2
(-6962 3712);
DISPLAY 0.489362 (-6962 3712);
PAINT MONO (-6962 3712);
FORCEPROP 1 LASTPIN (-7150 3700) $PN 2
J 2
(-7112 3712);
DISPLAY 0.489362 (-7112 3712);
PAINT MONO (-7112 3712);
FORCEPROP 1 LAST VALUE 33
J 0
(-6925 3700);
DISPLAY 0.489362 (-6925 3700);
PAINT SKYBLUE (-6925 3700);
FORCEPROP 2 LAST BOM_COST MEM
J 0
(-7075 3850);
DISPLAY 0.744681 (-7075 3850);
PAINT WHITE (-7075 3850);
DISPLAY INVISIBLE (-7075 3850);
FORCEPROP 2 LAST CDS_LIB pure_quanta
J 0
(-7050 3700);
DISPLAY INVISIBLE (-7050 3700);
FORCEPROP 1 LAST PATH I1305
J 2
(-7000 3850);
DISPLAY 0.978723 (-7000 3850);
PAINT WHITE (-7000 3850);
DISPLAY INVISIBLE (-7000 3850);
FORCEPROP 1 LAST WATTAGE 1/16W
J 0
(-6975 3625);
DISPLAY 0.489362 (-6975 3625);
PAINT SKYBLUE (-6975 3625);
DISPLAY INVISIBLE (-6975 3625);
FORCEPROP 1 LAST MATERIAL CHIP
J 0
(-7225 3675);
DISPLAY 0.489362 (-7225 3675);
PAINT SKYBLUE (-7225 3675);
DISPLAY INVISIBLE (-7225 3675);
FORCEPROP 1 LAST TOLERANCE 5%
J 2
(-6925 3675);
DISPLAY 0.489362 (-6925 3675);
PAINT SKYBLUE (-6925 3675);
DISPLAY INVISIBLE (-6925 3675);
FORCEPROP 1 LAST PART_NUMBER CS03302JB29
J 0
(-7150 3750);
DISPLAY 0.489362 (-7150 3750);
PAINT SKYBLUE (-7150 3750);
DISPLAY INVISIBLE (-7150 3750);
FORCEPROP 1 LAST PACK_TYPE 0402LF
J 0
(-7225 3625);
DISPLAY 0.489362 (-7225 3625);
PAINT SKYBLUE (-7225 3625);
DISPLAY INVISIBLE (-7225 3625);
FORCEPROP 2 LAST ROOM RST_CPU0_PLD_TO_DIMM
J 0
(-7075 3800);
DISPLAY 0.744681 (-7075 3800);
PAINT RED (-7075 3800);
DISPLAY INVISIBLE (-7075 3800);
FORCEADD Q_RES..1
R 2
(-7050 3750);
FORCEPROP 1 LAST LOCATION R60
J 0
(-7275 3750);
DISPLAY 0.489362 (-7275 3750);
PAINT SKYBLUE (-7275 3750);
FORCEPROP 0 LAST $SEC 1
J 0
(-7175 3800);
DISPLAY 0.680851 (-7175 3800);
PAINT MONO (-7175 3800);
DISPLAY INVISIBLE (-7175 3800);
FORCEPROP 0 LAST CDS_SEC 1
J 0
(-7175 3800);
DISPLAY 1.021277 (-7175 3800);
DISPLAY INVISIBLE (-7175 3800);
FORCEPROP 1 LASTPIN (-6950 3750) $PN 1
J 2
(-6962 3762);
DISPLAY 0.489362 (-6962 3762);
PAINT MONO (-6962 3762);
FORCEPROP 1 LASTPIN (-7150 3750) $PN 2
J 2
(-7112 3762);
DISPLAY 0.489362 (-7112 3762);
PAINT MONO (-7112 3762);
FORCEPROP 1 LAST VALUE 33
J 0
(-6925 3750);
DISPLAY 0.489362 (-6925 3750);
PAINT SKYBLUE (-6925 3750);
FORCEPROP 1 LAST MATERIAL EMPTY
J 0
(-7225 3725);
DISPLAY 0.489362 (-7225 3725);
PAINT RED (-7225 3725);
FORCEPROP 2 LAST ROOM RST_CPU0_PLD_TO_DIMM
J 0
(-7075 3850);
DISPLAY 0.744681 (-7075 3850);
PAINT RED (-7075 3850);
DISPLAY INVISIBLE (-7075 3850);
FORCEPROP 1 LAST PACK_TYPE 0402LF
J 0
(-7225 3675);
DISPLAY 0.489362 (-7225 3675);
PAINT SKYBLUE (-7225 3675);
DISPLAY INVISIBLE (-7225 3675);
FORCEPROP 1 LAST PART_NUMBER CS03302JB29
J 0
(-7150 3800);
DISPLAY 0.489362 (-7150 3800);
PAINT SKYBLUE (-7150 3800);
DISPLAY INVISIBLE (-7150 3800);
FORCEPROP 1 LAST TOLERANCE 5%
J 2
(-6925 3725);
DISPLAY 0.489362 (-6925 3725);
PAINT SKYBLUE (-6925 3725);
DISPLAY INVISIBLE (-6925 3725);
FORCEPROP 1 LAST WATTAGE 1/16W
J 0
(-6975 3675);
DISPLAY 0.489362 (-6975 3675);
PAINT SKYBLUE (-6975 3675);
DISPLAY INVISIBLE (-6975 3675);
FORCEPROP 1 LAST PATH I1306
J 2
(-7000 3900);
DISPLAY 0.978723 (-7000 3900);
PAINT WHITE (-7000 3900);
DISPLAY INVISIBLE (-7000 3900);
FORCEPROP 2 LAST BOM_COST MEM
J 0
(-7075 3900);
DISPLAY 0.744681 (-7075 3900);
PAINT WHITE (-7075 3900);
DISPLAY INVISIBLE (-7075 3900);
FORCEPROP 2 LAST CDS_LIB pure_quanta
J 0
(-7050 3750);
DISPLAY INVISIBLE (-7050 3750);
FORCEADD Q_RES..1
R 2
(-7050 3650);
FORCEPROP 1 LAST LOCATION R61
J 0
(-7275 3650);
DISPLAY 0.489362 (-7275 3650);
PAINT SKYBLUE (-7275 3650);
FORCEPROP 0 LAST $SEC 1
J 0
(-7175 3700);
DISPLAY 0.680851 (-7175 3700);
PAINT MONO (-7175 3700);
DISPLAY INVISIBLE (-7175 3700);
FORCEPROP 0 LAST CDS_SEC 1
J 0
(-7175 3700);
DISPLAY 1.021277 (-7175 3700);
DISPLAY INVISIBLE (-7175 3700);
FORCEPROP 1 LASTPIN (-6950 3650) $PN 1
J 2
(-6962 3662);
DISPLAY 0.489362 (-6962 3662);
PAINT MONO (-6962 3662);
FORCEPROP 1 LASTPIN (-7150 3650) $PN 2
J 2
(-7112 3662);
DISPLAY 0.489362 (-7112 3662);
PAINT MONO (-7112 3662);
FORCEPROP 1 LAST VALUE 33
J 0
(-6925 3650);
DISPLAY 0.489362 (-6925 3650);
PAINT SKYBLUE (-6925 3650);
FORCEPROP 1 LAST MATERIAL EMPTY
J 0
(-7225 3625);
DISPLAY 0.489362 (-7225 3625);
PAINT RED (-7225 3625);
FORCEPROP 2 LAST ROOM RST_CPU0_PLD_TO_DIMM
J 0
(-7075 3750);
DISPLAY 0.744681 (-7075 3750);
PAINT RED (-7075 3750);
DISPLAY INVISIBLE (-7075 3750);
FORCEPROP 1 LAST PACK_TYPE 0402LF
J 0
(-7225 3575);
DISPLAY 0.489362 (-7225 3575);
PAINT SKYBLUE (-7225 3575);
DISPLAY INVISIBLE (-7225 3575);
FORCEPROP 1 LAST PART_NUMBER CS03302JB29
J 0
(-7150 3700);
DISPLAY 0.489362 (-7150 3700);
PAINT SKYBLUE (-7150 3700);
DISPLAY INVISIBLE (-7150 3700);
FORCEPROP 1 LAST TOLERANCE 5%
J 2
(-6925 3625);
DISPLAY 0.489362 (-6925 3625);
PAINT SKYBLUE (-6925 3625);
DISPLAY INVISIBLE (-6925 3625);
FORCEPROP 1 LAST WATTAGE 1/16W
J 0
(-6975 3575);
DISPLAY 0.489362 (-6975 3575);
PAINT SKYBLUE (-6975 3575);
DISPLAY INVISIBLE (-6975 3575);
FORCEPROP 1 LAST PATH I1307
J 2
(-7000 3800);
DISPLAY 0.978723 (-7000 3800);
PAINT WHITE (-7000 3800);
DISPLAY INVISIBLE (-7000 3800);
FORCEPROP 2 LAST CDS_LIB pure_quanta
J 0
(-7050 3650);
DISPLAY INVISIBLE (-7050 3650);
FORCEPROP 2 LAST BOM_COST MEM
J 0
(-7075 3800);
DISPLAY 0.744681 (-7075 3800);
PAINT WHITE (-7075 3800);
DISPLAY INVISIBLE (-7075 3800);
FORCEADD Q_RES..1
R 2
(-7050 3600);
FORCEPROP 1 LAST LOCATION R62
J 0
(-7275 3600);
DISPLAY 0.489362 (-7275 3600);
PAINT SKYBLUE (-7275 3600);
FORCEPROP 0 LAST $SEC 1
J 0
(-7175 3650);
DISPLAY 0.680851 (-7175 3650);
PAINT MONO (-7175 3650);
DISPLAY INVISIBLE (-7175 3650);
FORCEPROP 0 LAST CDS_SEC 1
J 0
(-7175 3650);
DISPLAY 1.021277 (-7175 3650);
DISPLAY INVISIBLE (-7175 3650);
FORCEPROP 1 LASTPIN (-6950 3600) $PN 1
J 2
(-6962 3612);
DISPLAY 0.489362 (-6962 3612);
PAINT MONO (-6962 3612);
FORCEPROP 1 LASTPIN (-7150 3600) $PN 2
J 2
(-7112 3612);
DISPLAY 0.489362 (-7112 3612);
PAINT MONO (-7112 3612);
FORCEPROP 1 LAST VALUE 33
J 0
(-6925 3600);
DISPLAY 0.489362 (-6925 3600);
PAINT SKYBLUE (-6925 3600);
FORCEPROP 1 LAST MATERIAL EMPTY
J 0
(-7225 3575);
DISPLAY 0.489362 (-7225 3575);
PAINT RED (-7225 3575);
FORCEPROP 2 LAST ROOM RST_CPU0_PLD_TO_DIMM
J 0
(-7075 3700);
DISPLAY 0.744681 (-7075 3700);
PAINT RED (-7075 3700);
DISPLAY INVISIBLE (-7075 3700);
FORCEPROP 1 LAST PACK_TYPE 0402LF
J 0
(-7225 3525);
DISPLAY 0.489362 (-7225 3525);
PAINT SKYBLUE (-7225 3525);
DISPLAY INVISIBLE (-7225 3525);
FORCEPROP 1 LAST PART_NUMBER CS03302JB29
J 0
(-7150 3650);
DISPLAY 0.489362 (-7150 3650);
PAINT SKYBLUE (-7150 3650);
DISPLAY INVISIBLE (-7150 3650);
FORCEPROP 1 LAST TOLERANCE 5%
J 2
(-6925 3575);
DISPLAY 0.489362 (-6925 3575);
PAINT SKYBLUE (-6925 3575);
DISPLAY INVISIBLE (-6925 3575);
FORCEPROP 1 LAST WATTAGE 1/16W
J 0
(-6975 3525);
DISPLAY 0.489362 (-6975 3525);
PAINT SKYBLUE (-6975 3525);
DISPLAY INVISIBLE (-6975 3525);
FORCEPROP 1 LAST PATH I1308
J 2
(-7000 3750);
DISPLAY 0.978723 (-7000 3750);
PAINT WHITE (-7000 3750);
DISPLAY INVISIBLE (-7000 3750);
FORCEPROP 2 LAST BOM_COST MEM
J 0
(-7075 3750);
DISPLAY 0.744681 (-7075 3750);
PAINT WHITE (-7075 3750);
DISPLAY INVISIBLE (-7075 3750);
FORCEPROP 2 LAST CDS_LIB pure_quanta
J 0
(-7050 3600);
DISPLAY INVISIBLE (-7050 3600);
FORCEADD Q_RES..1
R 2
(-7050 3550);
FORCEPROP 1 LAST LOCATION R1129
J 0
(-7275 3550);
DISPLAY 0.489362 (-7275 3550);
PAINT SKYBLUE (-7275 3550);
FORCEPROP 0 LAST $SEC 1
J 0
(-7175 3600);
DISPLAY 0.680851 (-7175 3600);
PAINT MONO (-7175 3600);
DISPLAY INVISIBLE (-7175 3600);
FORCEPROP 0 LAST CDS_SEC 1
J 0
(-7175 3600);
DISPLAY 1.021277 (-7175 3600);
DISPLAY INVISIBLE (-7175 3600);
FORCEPROP 1 LASTPIN (-6950 3550) $PN 1
J 2
(-6962 3562);
DISPLAY 0.489362 (-6962 3562);
PAINT MONO (-6962 3562);
FORCEPROP 1 LASTPIN (-7150 3550) $PN 2
J 2
(-7112 3562);
DISPLAY 0.489362 (-7112 3562);
PAINT MONO (-7112 3562);
FORCEPROP 1 LAST VALUE 33
J 0
(-6925 3550);
DISPLAY 0.489362 (-6925 3550);
PAINT SKYBLUE (-6925 3550);
FORCEPROP 1 LAST MATERIAL EMPTY
J 0
(-7225 3525);
DISPLAY 0.489362 (-7225 3525);
PAINT RED (-7225 3525);
FORCEPROP 2 LAST ROOM RST_CPU0_PLD_TO_DIMM
J 0
(-7075 3650);
DISPLAY 0.744681 (-7075 3650);
PAINT RED (-7075 3650);
DISPLAY INVISIBLE (-7075 3650);
FORCEPROP 1 LAST PACK_TYPE 0402LF
J 0
(-7225 3475);
DISPLAY 0.489362 (-7225 3475);
PAINT SKYBLUE (-7225 3475);
DISPLAY INVISIBLE (-7225 3475);
FORCEPROP 1 LAST PART_NUMBER CS03302JB29
J 0
(-7150 3600);
DISPLAY 0.489362 (-7150 3600);
PAINT SKYBLUE (-7150 3600);
DISPLAY INVISIBLE (-7150 3600);
FORCEPROP 1 LAST TOLERANCE 5%
J 2
(-6925 3525);
DISPLAY 0.489362 (-6925 3525);
PAINT SKYBLUE (-6925 3525);
DISPLAY INVISIBLE (-6925 3525);
FORCEPROP 1 LAST WATTAGE 1/16W
J 0
(-6975 3475);
DISPLAY 0.489362 (-6975 3475);
PAINT SKYBLUE (-6975 3475);
DISPLAY INVISIBLE (-6975 3475);
FORCEPROP 1 LAST PATH I1309
J 2
(-7000 3700);
DISPLAY 0.978723 (-7000 3700);
PAINT WHITE (-7000 3700);
DISPLAY INVISIBLE (-7000 3700);
FORCEPROP 2 LAST BOM_COST MEM
J 0
(-7075 3700);
DISPLAY 0.744681 (-7075 3700);
PAINT WHITE (-7075 3700);
DISPLAY INVISIBLE (-7075 3700);
FORCEPROP 2 LAST CDS_LIB pure_quanta
J 0
(-7050 3550);
DISPLAY INVISIBLE (-7050 3550);
FORCEADD Q_RES..1
R 2
(-7050 3400);
FORCEPROP 1 LAST LOCATION R23
J 0
(-7275 3400);
DISPLAY 0.489362 (-7275 3400);
PAINT SKYBLUE (-7275 3400);
FORCEPROP 0 LAST $SEC 1
J 0
(-7275 3450);
DISPLAY 0.680851 (-7275 3450);
PAINT MONO (-7275 3450);
DISPLAY INVISIBLE (-7275 3450);
FORCEPROP 0 LAST CDS_SEC 1
J 0
(-7275 3450);
DISPLAY 0.680851 (-7275 3450);
DISPLAY INVISIBLE (-7275 3450);
FORCEPROP 1 LASTPIN (-6950 3400) $PN 1
J 2
(-6962 3412);
DISPLAY 0.489362 (-6962 3412);
PAINT MONO (-6962 3412);
FORCEPROP 1 LASTPIN (-7150 3400) $PN 2
J 2
(-7112 3412);
DISPLAY 0.489362 (-7112 3412);
PAINT MONO (-7112 3412);
FORCEPROP 1 LAST VALUE 33
J 0
(-6925 3400);
DISPLAY 0.489362 (-6925 3400);
PAINT SKYBLUE (-6925 3400);
FORCEPROP 2 LAST CDS_LIB pure_quanta
J 0
(-7050 3400);
DISPLAY INVISIBLE (-7050 3400);
FORCEPROP 2 LAST BOM_COST MEM
J 0
(-7075 3550);
DISPLAY 0.744681 (-7075 3550);
PAINT WHITE (-7075 3550);
DISPLAY INVISIBLE (-7075 3550);
FORCEPROP 1 LAST PATH I1310
J 2
(-7000 3550);
DISPLAY 0.978723 (-7000 3550);
PAINT WHITE (-7000 3550);
DISPLAY INVISIBLE (-7000 3550);
FORCEPROP 1 LAST WATTAGE 1/16W
J 0
(-6975 3325);
DISPLAY 0.489362 (-6975 3325);
PAINT SKYBLUE (-6975 3325);
DISPLAY INVISIBLE (-6975 3325);
FORCEPROP 1 LAST MATERIAL CHIP
J 0
(-7225 3375);
DISPLAY 0.489362 (-7225 3375);
PAINT SKYBLUE (-7225 3375);
DISPLAY INVISIBLE (-7225 3375);
FORCEPROP 1 LAST TOLERANCE 5%
J 2
(-6925 3375);
DISPLAY 0.489362 (-6925 3375);
PAINT SKYBLUE (-6925 3375);
DISPLAY INVISIBLE (-6925 3375);
FORCEPROP 1 LAST PART_NUMBER CS03302JB29
J 0
(-7150 3450);
DISPLAY 0.489362 (-7150 3450);
PAINT SKYBLUE (-7150 3450);
DISPLAY INVISIBLE (-7150 3450);
FORCEPROP 1 LAST PACK_TYPE 0402LF
J 0
(-7225 3325);
DISPLAY 0.489362 (-7225 3325);
PAINT SKYBLUE (-7225 3325);
DISPLAY INVISIBLE (-7225 3325);
FORCEPROP 2 LAST ROOM RST_CPU0_PLD_TO_DIMM
J 0
(-7075 3500);
DISPLAY 0.744681 (-7075 3500);
PAINT RED (-7075 3500);
DISPLAY INVISIBLE (-7075 3500);
FORCEADD Q_RES..1
R 2
(-7050 3250);
FORCEPROP 1 LAST LOCATION R154
J 0
(-7275 3250);
DISPLAY 0.489362 (-7275 3250);
PAINT SKYBLUE (-7275 3250);
FORCEPROP 0 LAST $SEC 1
J 0
(-7175 3300);
DISPLAY 0.680851 (-7175 3300);
PAINT MONO (-7175 3300);
DISPLAY INVISIBLE (-7175 3300);
FORCEPROP 0 LAST CDS_SEC 1
J 0
(-7175 3300);
DISPLAY 1.021277 (-7175 3300);
DISPLAY INVISIBLE (-7175 3300);
FORCEPROP 1 LASTPIN (-6950 3250) $PN 1
J 2
(-6962 3262);
DISPLAY 0.489362 (-6962 3262);
PAINT MONO (-6962 3262);
FORCEPROP 1 LASTPIN (-7150 3250) $PN 2
J 2
(-7112 3262);
DISPLAY 0.489362 (-7112 3262);
PAINT MONO (-7112 3262);
FORCEPROP 1 LAST MATERIAL EMPTY
J 0
(-7225 3225);
DISPLAY 0.489362 (-7225 3225);
PAINT RED (-7225 3225);
FORCEPROP 1 LAST VALUE 33
J 0
(-6925 3250);
DISPLAY 0.489362 (-6925 3250);
PAINT SKYBLUE (-6925 3250);
FORCEPROP 2 LAST ROOM RST_CPU0_PLD_TO_DIMM
J 0
(-7075 3350);
DISPLAY 0.744681 (-7075 3350);
PAINT RED (-7075 3350);
DISPLAY INVISIBLE (-7075 3350);
FORCEPROP 1 LAST PACK_TYPE 0402LF
J 0
(-7225 3175);
DISPLAY 0.489362 (-7225 3175);
PAINT SKYBLUE (-7225 3175);
DISPLAY INVISIBLE (-7225 3175);
FORCEPROP 1 LAST PART_NUMBER CS03302JB29
J 0
(-7150 3300);
DISPLAY 0.489362 (-7150 3300);
PAINT SKYBLUE (-7150 3300);
DISPLAY INVISIBLE (-7150 3300);
FORCEPROP 1 LAST TOLERANCE 5%
J 2
(-6925 3225);
DISPLAY 0.489362 (-6925 3225);
PAINT SKYBLUE (-6925 3225);
DISPLAY INVISIBLE (-6925 3225);
FORCEPROP 1 LAST WATTAGE 1/16W
J 0
(-6975 3175);
DISPLAY 0.489362 (-6975 3175);
PAINT SKYBLUE (-6975 3175);
DISPLAY INVISIBLE (-6975 3175);
FORCEPROP 1 LAST PATH I1311
J 2
(-7000 3400);
DISPLAY 0.978723 (-7000 3400);
PAINT WHITE (-7000 3400);
DISPLAY INVISIBLE (-7000 3400);
FORCEPROP 2 LAST BOM_COST MEM
J 0
(-7075 3400);
DISPLAY 0.744681 (-7075 3400);
PAINT WHITE (-7075 3400);
DISPLAY INVISIBLE (-7075 3400);
FORCEPROP 2 LAST CDS_LIB pure_quanta
J 0
(-7050 3250);
DISPLAY INVISIBLE (-7050 3250);
FORCEADD Q_RES..1
R 2
(-7050 3300);
FORCEPROP 1 LAST LOCATION R152
J 0
(-7275 3300);
DISPLAY 0.489362 (-7275 3300);
PAINT SKYBLUE (-7275 3300);
FORCEPROP 0 LAST $SEC 1
J 0
(-7275 3350);
DISPLAY 0.680851 (-7275 3350);
PAINT MONO (-7275 3350);
DISPLAY INVISIBLE (-7275 3350);
FORCEPROP 0 LAST CDS_SEC 1
J 0
(-7275 3350);
DISPLAY 0.680851 (-7275 3350);
DISPLAY INVISIBLE (-7275 3350);
FORCEPROP 1 LASTPIN (-6950 3300) $PN 1
J 2
(-6962 3312);
DISPLAY 0.489362 (-6962 3312);
PAINT MONO (-6962 3312);
FORCEPROP 1 LASTPIN (-7150 3300) $PN 2
J 2
(-7112 3312);
DISPLAY 0.489362 (-7112 3312);
PAINT MONO (-7112 3312);
FORCEPROP 1 LAST VALUE 33
J 0
(-6925 3300);
DISPLAY 0.489362 (-6925 3300);
PAINT SKYBLUE (-6925 3300);
FORCEPROP 2 LAST CDS_LIB pure_quanta
J 0
(-7050 3300);
DISPLAY INVISIBLE (-7050 3300);
FORCEPROP 2 LAST BOM_COST MEM
J 0
(-7075 3450);
DISPLAY 0.744681 (-7075 3450);
PAINT WHITE (-7075 3450);
DISPLAY INVISIBLE (-7075 3450);
FORCEPROP 1 LAST PATH I1312
J 2
(-7000 3450);
DISPLAY 0.978723 (-7000 3450);
PAINT WHITE (-7000 3450);
DISPLAY INVISIBLE (-7000 3450);
FORCEPROP 1 LAST WATTAGE 1/16W
J 0
(-6975 3225);
DISPLAY 0.489362 (-6975 3225);
PAINT SKYBLUE (-6975 3225);
DISPLAY INVISIBLE (-6975 3225);
FORCEPROP 1 LAST MATERIAL CHIP
J 0
(-7225 3275);
DISPLAY 0.489362 (-7225 3275);
PAINT SKYBLUE (-7225 3275);
DISPLAY INVISIBLE (-7225 3275);
FORCEPROP 1 LAST TOLERANCE 5%
J 2
(-6925 3275);
DISPLAY 0.489362 (-6925 3275);
PAINT SKYBLUE (-6925 3275);
DISPLAY INVISIBLE (-6925 3275);
FORCEPROP 1 LAST PART_NUMBER CS03302JB29
J 0
(-7150 3350);
DISPLAY 0.489362 (-7150 3350);
PAINT SKYBLUE (-7150 3350);
DISPLAY INVISIBLE (-7150 3350);
FORCEPROP 1 LAST PACK_TYPE 0402LF
J 0
(-7225 3225);
DISPLAY 0.489362 (-7225 3225);
PAINT SKYBLUE (-7225 3225);
DISPLAY INVISIBLE (-7225 3225);
FORCEPROP 2 LAST ROOM RST_CPU0_PLD_TO_DIMM
J 0
(-7075 3400);
DISPLAY 0.744681 (-7075 3400);
PAINT RED (-7075 3400);
DISPLAY INVISIBLE (-7075 3400);
FORCEADD OFFPAGE..2
R 2
(-8075 5000);
FORCEPROP 2 LAST $XR1 136 
J 0
(-8449 5000);
DISPLAY 0.638298 (-8449 5000);
PAINT MONO (-8449 5000);
FORCEPROP 2 LAST $XR0 82 
J 0
(-8329 5000);
DISPLAY 0.638298 (-8329 5000);
PAINT MONO (-8329 5000);
FORCEPROP 2 LAST PATH I1313
J 0
(-8025 5075);
DISPLAY 0.680851 (-8025 5075);
DISPLAY INVISIBLE (-8025 5075);
FORCEPROP 1 LAST COMMENT_BODY TRUE
J 2
(-8030 4905);
DISPLAY 0.872340 (-8030 4905);
PAINT GREEN (-8030 4905);
DISPLAY INVISIBLE (-8030 4905);
FORCEPROP 1 LAST OFFPAGE TRUE
J 2
(-8400 4875);
DISPLAY 0.872340 (-8400 4875);
PAINT GREEN (-8400 4875);
DISPLAY INVISIBLE (-8400 4875);
FORCEPROP 2 LAST CDS_LIB standard
J 0
(-8075 5000);
DISPLAY INVISIBLE (-8075 5000);
FORCEADD OFFPAGE..2
R 2
(-8075 4950);
FORCEPROP 2 LAST $XR0 136 
J 0
(-8360 4950);
DISPLAY 0.638298 (-8360 4950);
PAINT MONO (-8360 4950);
FORCEPROP 2 LAST PATH I1314
J 0
(-8025 5025);
DISPLAY 0.680851 (-8025 5025);
DISPLAY INVISIBLE (-8025 5025);
FORCEPROP 2 LAST CDS_LIB standard
J 0
(-8075 4950);
DISPLAY INVISIBLE (-8075 4950);
FORCEPROP 1 LAST COMMENT_BODY TRUE
J 2
(-8030 4855);
DISPLAY 0.872340 (-8030 4855);
PAINT GREEN (-8030 4855);
DISPLAY INVISIBLE (-8030 4855);
FORCEPROP 1 LAST OFFPAGE TRUE
J 2
(-8400 4825);
DISPLAY 0.872340 (-8400 4825);
PAINT GREEN (-8400 4825);
DISPLAY INVISIBLE (-8400 4825);
FORCEADD OFFPAGE..2
R 2
(-8075 4700);
FORCEPROP 2 LAST $XR0 136 
J 0
(-8360 4700);
DISPLAY 0.638298 (-8360 4700);
PAINT MONO (-8360 4700);
FORCEPROP 2 LAST PATH I1315
J 0
(-8025 4775);
DISPLAY 0.680851 (-8025 4775);
DISPLAY INVISIBLE (-8025 4775);
FORCEPROP 1 LAST COMMENT_BODY TRUE
J 2
(-8030 4605);
DISPLAY 0.872340 (-8030 4605);
PAINT GREEN (-8030 4605);
DISPLAY INVISIBLE (-8030 4605);
FORCEPROP 1 LAST OFFPAGE TRUE
J 2
(-8400 4575);
DISPLAY 0.872340 (-8400 4575);
PAINT GREEN (-8400 4575);
DISPLAY INVISIBLE (-8400 4575);
FORCEPROP 2 LAST CDS_LIB standard
J 0
(-8075 4700);
DISPLAY INVISIBLE (-8075 4700);
FORCEADD OFFPAGE..2
R 2
(-8075 4750);
FORCEPROP 2 LAST $XR0 148 
J 0
(-8360 4750);
DISPLAY 0.638298 (-8360 4750);
PAINT MONO (-8360 4750);
FORCEPROP 2 LAST PATH I1316
J 0
(-8025 4825);
DISPLAY 0.680851 (-8025 4825);
DISPLAY INVISIBLE (-8025 4825);
FORCEPROP 2 LAST CDS_LIB standard
J 0
(-8075 4750);
DISPLAY INVISIBLE (-8075 4750);
FORCEPROP 1 LAST COMMENT_BODY TRUE
J 2
(-8030 4655);
DISPLAY 0.872340 (-8030 4655);
PAINT GREEN (-8030 4655);
DISPLAY INVISIBLE (-8030 4655);
FORCEPROP 1 LAST OFFPAGE TRUE
J 2
(-8400 4625);
DISPLAY 0.872340 (-8400 4625);
PAINT GREEN (-8400 4625);
DISPLAY INVISIBLE (-8400 4625);
FORCEADD OFFPAGE..2
R 2
(-8075 4900);
FORCEPROP 2 LAST $XR1 136 
J 0
(-8449 4900);
DISPLAY 0.638298 (-8449 4900);
PAINT MONO (-8449 4900);
FORCEPROP 2 LAST $XR0 82 
J 0
(-8329 4900);
DISPLAY 0.638298 (-8329 4900);
PAINT MONO (-8329 4900);
FORCEPROP 2 LAST PATH I1317
J 0
(-8025 4975);
DISPLAY 0.680851 (-8025 4975);
DISPLAY INVISIBLE (-8025 4975);
FORCEPROP 2 LAST CDS_LIB standard
J 0
(-8075 4900);
DISPLAY INVISIBLE (-8075 4900);
FORCEPROP 1 LAST COMMENT_BODY TRUE
J 2
(-8030 4805);
DISPLAY 0.872340 (-8030 4805);
PAINT GREEN (-8030 4805);
DISPLAY INVISIBLE (-8030 4805);
FORCEPROP 1 LAST OFFPAGE TRUE
J 2
(-8400 4775);
DISPLAY 0.872340 (-8400 4775);
PAINT GREEN (-8400 4775);
DISPLAY INVISIBLE (-8400 4775);
FORCEADD OFFPAGE..2
R 2
(-8075 4800);
FORCEPROP 2 LAST $XR1 136 
J 0
(-8449 4800);
DISPLAY 0.638298 (-8449 4800);
PAINT MONO (-8449 4800);
FORCEPROP 2 LAST $XR0 82 
J 0
(-8329 4800);
DISPLAY 0.638298 (-8329 4800);
PAINT MONO (-8329 4800);
FORCEPROP 2 LAST PATH I1318
J 0
(-8025 4875);
DISPLAY 0.680851 (-8025 4875);
DISPLAY INVISIBLE (-8025 4875);
FORCEPROP 2 LAST CDS_LIB standard
J 0
(-8075 4800);
DISPLAY INVISIBLE (-8075 4800);
FORCEPROP 1 LAST COMMENT_BODY TRUE
J 2
(-8030 4705);
DISPLAY 0.872340 (-8030 4705);
PAINT GREEN (-8030 4705);
DISPLAY INVISIBLE (-8030 4705);
FORCEPROP 1 LAST OFFPAGE TRUE
J 2
(-8400 4675);
DISPLAY 0.872340 (-8400 4675);
PAINT GREEN (-8400 4675);
DISPLAY INVISIBLE (-8400 4675);
FORCEADD OFFPAGE..2
R 2
(-8075 4850);
FORCEPROP 2 LAST $XR0 136 
J 0
(-8360 4850);
DISPLAY 0.638298 (-8360 4850);
PAINT MONO (-8360 4850);
FORCEPROP 2 LAST PATH I1319
J 0
(-8025 4925);
DISPLAY 0.680851 (-8025 4925);
DISPLAY INVISIBLE (-8025 4925);
FORCEPROP 2 LAST CDS_LIB standard
J 0
(-8075 4850);
DISPLAY INVISIBLE (-8075 4850);
FORCEPROP 1 LAST COMMENT_BODY TRUE
J 2
(-8030 4755);
DISPLAY 0.872340 (-8030 4755);
PAINT GREEN (-8030 4755);
DISPLAY INVISIBLE (-8030 4755);
FORCEPROP 1 LAST OFFPAGE TRUE
J 2
(-8400 4725);
DISPLAY 0.872340 (-8400 4725);
PAINT GREEN (-8400 4725);
DISPLAY INVISIBLE (-8400 4725);
FORCEADD OFFPAGE..2
R 2
(-8075 4650);
FORCEPROP 2 LAST $XR1 136 
J 0
(-8449 4650);
DISPLAY 0.638298 (-8449 4650);
PAINT MONO (-8449 4650);
FORCEPROP 2 LAST $XR0 82 
J 0
(-8329 4650);
DISPLAY 0.638298 (-8329 4650);
PAINT MONO (-8329 4650);
FORCEPROP 2 LAST PATH I1320
J 0
(-8025 4725);
DISPLAY 0.680851 (-8025 4725);
DISPLAY INVISIBLE (-8025 4725);
FORCEPROP 1 LAST OFFPAGE TRUE
J 2
(-8400 4525);
DISPLAY 0.872340 (-8400 4525);
PAINT GREEN (-8400 4525);
DISPLAY INVISIBLE (-8400 4525);
FORCEPROP 1 LAST COMMENT_BODY TRUE
J 2
(-8030 4555);
DISPLAY 0.872340 (-8030 4555);
PAINT GREEN (-8030 4555);
DISPLAY INVISIBLE (-8030 4555);
FORCEPROP 2 LAST CDS_LIB standard
J 0
(-8075 4650);
DISPLAY INVISIBLE (-8075 4650);
FORCEADD OFFPAGE..2
R 2
(-8075 4450);
FORCEPROP 2 LAST $XR0 117 
J 0
(-8360 4450);
DISPLAY 0.638298 (-8360 4450);
PAINT MONO (-8360 4450);
FORCEPROP 2 LAST PATH I1321
J 0
(-8025 4525);
DISPLAY 0.680851 (-8025 4525);
DISPLAY INVISIBLE (-8025 4525);
FORCEPROP 2 LAST CDS_LIB standard
J 0
(-8075 4450);
DISPLAY INVISIBLE (-8075 4450);
FORCEPROP 1 LAST COMMENT_BODY TRUE
J 2
(-8030 4355);
DISPLAY 0.872340 (-8030 4355);
PAINT GREEN (-8030 4355);
DISPLAY INVISIBLE (-8030 4355);
FORCEPROP 1 LAST OFFPAGE TRUE
J 2
(-8400 4325);
DISPLAY 0.872340 (-8400 4325);
PAINT GREEN (-8400 4325);
DISPLAY INVISIBLE (-8400 4325);
FORCEADD OFFPAGE..2
R 2
(-8075 4550);
FORCEPROP 2 LAST $XR1 117 
J 0
(-8480 4550);
DISPLAY 0.638298 (-8480 4550);
PAINT MONO (-8480 4550);
FORCEPROP 2 LAST $XR0 118 
J 0
(-8360 4550);
DISPLAY 0.638298 (-8360 4550);
PAINT MONO (-8360 4550);
FORCEPROP 2 LAST PATH I1322
J 0
(-8025 4625);
DISPLAY 0.680851 (-8025 4625);
DISPLAY INVISIBLE (-8025 4625);
FORCEPROP 2 LAST CDS_LIB standard
J 0
(-8075 4550);
DISPLAY INVISIBLE (-8075 4550);
FORCEPROP 1 LAST COMMENT_BODY TRUE
J 2
(-8030 4455);
DISPLAY 0.872340 (-8030 4455);
PAINT GREEN (-8030 4455);
DISPLAY INVISIBLE (-8030 4455);
FORCEPROP 1 LAST OFFPAGE TRUE
J 2
(-8400 4425);
DISPLAY 0.872340 (-8400 4425);
PAINT GREEN (-8400 4425);
DISPLAY INVISIBLE (-8400 4425);
FORCEADD OFFPAGE..2
R 2
(-8075 4600);
FORCEPROP 2 LAST $XR0 148 
J 0
(-8360 4600);
DISPLAY 0.638298 (-8360 4600);
PAINT MONO (-8360 4600);
FORCEPROP 2 LAST PATH I1323
J 0
(-8025 4675);
DISPLAY 0.680851 (-8025 4675);
DISPLAY INVISIBLE (-8025 4675);
FORCEPROP 2 LAST CDS_LIB standard
J 0
(-8075 4600);
DISPLAY INVISIBLE (-8075 4600);
FORCEPROP 1 LAST COMMENT_BODY TRUE
J 2
(-8030 4505);
DISPLAY 0.872340 (-8030 4505);
PAINT GREEN (-8030 4505);
DISPLAY INVISIBLE (-8030 4505);
FORCEPROP 1 LAST OFFPAGE TRUE
J 2
(-8400 4475);
DISPLAY 0.872340 (-8400 4475);
PAINT GREEN (-8400 4475);
DISPLAY INVISIBLE (-8400 4475);
FORCEADD OFFPAGE..4
R 2
(-8075 4400);
FORCEPROP 2 LAST $XR1 118 
J 0
(-8477 4400);
DISPLAY 0.638298 (-8477 4400);
PAINT MONO (-8477 4400);
FORCEPROP 2 LAST $XR0 117 
J 0
(-8357 4400);
DISPLAY 0.638298 (-8357 4400);
PAINT MONO (-8357 4400);
FORCEPROP 2 LAST PATH I1324
J 0
(-8025 4475);
DISPLAY 0.680851 (-8025 4475);
DISPLAY INVISIBLE (-8025 4475);
FORCEPROP 2 LAST CDS_LIB standard
J 0
(-8075 4400);
DISPLAY INVISIBLE (-8075 4400);
FORCEPROP 1 LAST OFFPAGE TRUE
J 2
(-8400 4275);
DISPLAY 0.872340 (-8400 4275);
PAINT GREEN (-8400 4275);
DISPLAY INVISIBLE (-8400 4275);
FORCEPROP 1 LAST COMMENT_BODY TRUE
J 2
(-8050 4300);
DISPLAY 0.872340 (-8050 4300);
PAINT GREEN (-8050 4300);
DISPLAY INVISIBLE (-8050 4300);
FORCEADD OFFPAGE..4
R 2
(-8075 4350);
FORCEPROP 2 LAST $XR0 117 
J 0
(-8327 4350);
DISPLAY 0.638298 (-8327 4350);
PAINT MONO (-8327 4350);
FORCEPROP 1 LAST COMMENT_BODY TRUE
J 2
(-8050 4250);
DISPLAY 0.872340 (-8050 4250);
PAINT GREEN (-8050 4250);
DISPLAY INVISIBLE (-8050 4250);
FORCEPROP 1 LAST OFFPAGE TRUE
J 2
(-8400 4225);
DISPLAY 0.872340 (-8400 4225);
PAINT GREEN (-8400 4225);
DISPLAY INVISIBLE (-8400 4225);
FORCEPROP 2 LAST PATH I1325
J 0
(-8025 4425);
DISPLAY 0.680851 (-8025 4425);
DISPLAY INVISIBLE (-8025 4425);
FORCEPROP 2 LAST CDS_LIB standard
J 0
(-8075 4350);
DISPLAY INVISIBLE (-8075 4350);
FORCEADD OFFPAGE..2
R 2
(-8075 4300);
FORCEPROP 2 LAST $XR0 136 
J 0
(-8360 4300);
DISPLAY 0.638298 (-8360 4300);
PAINT MONO (-8360 4300);
FORCEPROP 2 LAST PATH I1326
J 0
(-8025 4375);
DISPLAY 0.680851 (-8025 4375);
DISPLAY INVISIBLE (-8025 4375);
FORCEPROP 2 LAST CDS_LIB standard
J 0
(-8075 4300);
DISPLAY INVISIBLE (-8075 4300);
FORCEPROP 1 LAST COMMENT_BODY TRUE
J 2
(-8030 4205);
DISPLAY 0.872340 (-8030 4205);
PAINT GREEN (-8030 4205);
DISPLAY INVISIBLE (-8030 4205);
FORCEPROP 1 LAST OFFPAGE TRUE
J 2
(-8400 4175);
DISPLAY 0.872340 (-8400 4175);
PAINT GREEN (-8400 4175);
DISPLAY INVISIBLE (-8400 4175);
FORCEADD OFFPAGE..4
R 2
(-8075 4200);
FORCEPROP 2 LAST $XR1 118 
J 0
(-8447 4200);
DISPLAY 0.638298 (-8447 4200);
PAINT MONO (-8447 4200);
FORCEPROP 2 LAST $XR0 117 
J 0
(-8327 4200);
DISPLAY 0.638298 (-8327 4200);
PAINT MONO (-8327 4200);
FORCEPROP 1 LAST COMMENT_BODY TRUE
J 2
(-8050 4100);
DISPLAY 0.872340 (-8050 4100);
PAINT GREEN (-8050 4100);
DISPLAY INVISIBLE (-8050 4100);
FORCEPROP 1 LAST OFFPAGE TRUE
J 2
(-8400 4075);
DISPLAY 0.872340 (-8400 4075);
PAINT GREEN (-8400 4075);
DISPLAY INVISIBLE (-8400 4075);
FORCEPROP 2 LAST PATH I1327
J 0
(-8025 4275);
DISPLAY 0.680851 (-8025 4275);
DISPLAY INVISIBLE (-8025 4275);
FORCEPROP 2 LAST CDS_LIB standard
J 0
(-8075 4200);
DISPLAY INVISIBLE (-8075 4200);
FORCEADD OFFPAGE..4
R 2
(-8075 4150);
FORCEPROP 2 LAST $XR0 211 
J 0
(-8327 4150);
DISPLAY 0.638298 (-8327 4150);
PAINT MONO (-8327 4150);
FORCEPROP 2 LAST PATH I1328
J 0
(-8025 4225);
DISPLAY 0.680851 (-8025 4225);
DISPLAY INVISIBLE (-8025 4225);
FORCEPROP 2 LAST CDS_LIB standard
J 0
(-8075 4150);
DISPLAY INVISIBLE (-8075 4150);
FORCEPROP 1 LAST OFFPAGE TRUE
J 2
(-8400 4025);
DISPLAY 0.872340 (-8400 4025);
PAINT GREEN (-8400 4025);
DISPLAY INVISIBLE (-8400 4025);
FORCEPROP 1 LAST COMMENT_BODY TRUE
J 2
(-8050 4050);
DISPLAY 0.872340 (-8050 4050);
PAINT GREEN (-8050 4050);
DISPLAY INVISIBLE (-8050 4050);
FORCEADD OFFPAGE..4
R 2
(-8075 3950);
FORCEPROP 2 LAST $XR0 211 
J 0
(-8357 3950);
DISPLAY 0.638298 (-8357 3950);
PAINT MONO (-8357 3950);
FORCEPROP 2 LAST PATH I1329
J 0
(-8025 4025);
DISPLAY 0.680851 (-8025 4025);
DISPLAY INVISIBLE (-8025 4025);
FORCEPROP 2 LAST CDS_LIB standard
J 0
(-8075 3950);
DISPLAY INVISIBLE (-8075 3950);
FORCEPROP 1 LAST OFFPAGE TRUE
J 2
(-8400 3825);
DISPLAY 0.872340 (-8400 3825);
PAINT GREEN (-8400 3825);
DISPLAY INVISIBLE (-8400 3825);
FORCEPROP 1 LAST COMMENT_BODY TRUE
J 2
(-8050 3850);
DISPLAY 0.872340 (-8050 3850);
PAINT GREEN (-8050 3850);
DISPLAY INVISIBLE (-8050 3850);
FORCEADD OFFPAGE..2
R 2
(-8075 4000);
FORCEPROP 2 LAST $XR0 211 
J 0
(-8360 4000);
DISPLAY 0.638298 (-8360 4000);
PAINT MONO (-8360 4000);
FORCEPROP 2 LAST PATH I1330
J 0
(-8025 4075);
DISPLAY 0.680851 (-8025 4075);
DISPLAY INVISIBLE (-8025 4075);
FORCEPROP 2 LAST CDS_LIB standard
J 0
(-8075 4000);
DISPLAY INVISIBLE (-8075 4000);
FORCEPROP 1 LAST COMMENT_BODY TRUE
J 2
(-8030 3905);
DISPLAY 0.872340 (-8030 3905);
PAINT GREEN (-8030 3905);
DISPLAY INVISIBLE (-8030 3905);
FORCEPROP 1 LAST OFFPAGE TRUE
J 2
(-8400 3875);
DISPLAY 0.872340 (-8400 3875);
PAINT GREEN (-8400 3875);
DISPLAY INVISIBLE (-8400 3875);
FORCEADD OFFPAGE..4
R 2
(-8075 4100);
FORCEPROP 2 LAST $XR1 118 
J 0
(-8447 4100);
DISPLAY 0.638298 (-8447 4100);
PAINT MONO (-8447 4100);
FORCEPROP 2 LAST $XR0 117 
J 0
(-8327 4100);
DISPLAY 0.638298 (-8327 4100);
PAINT MONO (-8327 4100);
FORCEPROP 2 LAST PATH I1331
J 0
(-8025 4175);
DISPLAY 0.680851 (-8025 4175);
DISPLAY INVISIBLE (-8025 4175);
FORCEPROP 2 LAST CDS_LIB standard
J 0
(-8075 4100);
DISPLAY INVISIBLE (-8075 4100);
FORCEPROP 1 LAST OFFPAGE TRUE
J 2
(-8400 3975);
DISPLAY 0.872340 (-8400 3975);
PAINT GREEN (-8400 3975);
DISPLAY INVISIBLE (-8400 3975);
FORCEPROP 1 LAST COMMENT_BODY TRUE
J 2
(-8050 4000);
DISPLAY 0.872340 (-8050 4000);
PAINT GREEN (-8050 4000);
DISPLAY INVISIBLE (-8050 4000);
FORCEADD OFFPAGE..4
R 2
(-8075 4050);
FORCEPROP 2 LAST $XR1 118 
J 0
(-8447 4050);
DISPLAY 0.638298 (-8447 4050);
PAINT MONO (-8447 4050);
FORCEPROP 2 LAST $XR0 117 
J 0
(-8327 4050);
DISPLAY 0.638298 (-8327 4050);
PAINT MONO (-8327 4050);
FORCEPROP 2 LAST PATH I1332
J 0
(-8025 4125);
DISPLAY 0.680851 (-8025 4125);
DISPLAY INVISIBLE (-8025 4125);
FORCEPROP 2 LAST CDS_LIB standard
J 0
(-8075 4050);
DISPLAY INVISIBLE (-8075 4050);
FORCEPROP 1 LAST OFFPAGE TRUE
J 2
(-8400 3925);
DISPLAY 0.872340 (-8400 3925);
PAINT GREEN (-8400 3925);
DISPLAY INVISIBLE (-8400 3925);
FORCEPROP 1 LAST COMMENT_BODY TRUE
J 2
(-8050 3950);
DISPLAY 0.872340 (-8050 3950);
PAINT GREEN (-8050 3950);
DISPLAY INVISIBLE (-8050 3950);
FORCEADD OFFPAGE..2
R 2
(-8075 3900);
FORCEPROP 2 LAST $XR1 117 
J 0
(-8480 3900);
DISPLAY 0.638298 (-8480 3900);
PAINT MONO (-8480 3900);
FORCEPROP 2 LAST $XR0 118 
J 0
(-8360 3900);
DISPLAY 0.638298 (-8360 3900);
PAINT MONO (-8360 3900);
FORCEPROP 2 LAST PATH I1333
J 0
(-8025 3975);
DISPLAY 0.680851 (-8025 3975);
DISPLAY INVISIBLE (-8025 3975);
FORCEPROP 2 LAST CDS_LIB standard
J 0
(-8075 3900);
DISPLAY INVISIBLE (-8075 3900);
FORCEPROP 1 LAST COMMENT_BODY TRUE
J 2
(-8030 3805);
DISPLAY 0.872340 (-8030 3805);
PAINT GREEN (-8030 3805);
DISPLAY INVISIBLE (-8030 3805);
FORCEPROP 1 LAST OFFPAGE TRUE
J 2
(-8400 3775);
DISPLAY 0.872340 (-8400 3775);
PAINT GREEN (-8400 3775);
DISPLAY INVISIBLE (-8400 3775);
FORCEADD OFFPAGE..2
R 2
(-8075 3700);
FORCEPROP 2 LAST $XR0 211 
J 0
(-8360 3700);
DISPLAY 0.638298 (-8360 3700);
PAINT MONO (-8360 3700);
FORCEPROP 2 LAST PATH I1334
J 0
(-8025 3775);
DISPLAY 0.680851 (-8025 3775);
DISPLAY INVISIBLE (-8025 3775);
FORCEPROP 1 LAST COMMENT_BODY TRUE
J 2
(-8030 3605);
DISPLAY 0.872340 (-8030 3605);
PAINT GREEN (-8030 3605);
DISPLAY INVISIBLE (-8030 3605);
FORCEPROP 1 LAST OFFPAGE TRUE
J 2
(-8400 3575);
DISPLAY 0.872340 (-8400 3575);
PAINT GREEN (-8400 3575);
DISPLAY INVISIBLE (-8400 3575);
FORCEPROP 2 LAST CDS_LIB standard
J 0
(-8075 3700);
DISPLAY INVISIBLE (-8075 3700);
FORCEADD OFFPAGE..2
R 2
(-8075 3750);
FORCEPROP 2 LAST $XR1 114 
J 0
(-8480 3750);
DISPLAY 0.638298 (-8480 3750);
PAINT MONO (-8480 3750);
FORCEPROP 2 LAST $XR0 133 
J 0
(-8360 3750);
DISPLAY 0.638298 (-8360 3750);
PAINT MONO (-8360 3750);
FORCEPROP 2 LAST CDS_LIB standard
J 0
(-8075 3750);
DISPLAY INVISIBLE (-8075 3750);
FORCEPROP 2 LAST PATH I1335
J 0
(-8025 3825);
DISPLAY 0.680851 (-8025 3825);
DISPLAY INVISIBLE (-8025 3825);
FORCEPROP 1 LAST OFFPAGE TRUE
J 2
(-8400 3625);
DISPLAY 0.872340 (-8400 3625);
PAINT GREEN (-8400 3625);
DISPLAY INVISIBLE (-8400 3625);
FORCEPROP 1 LAST COMMENT_BODY TRUE
J 2
(-8030 3655);
DISPLAY 0.872340 (-8030 3655);
PAINT GREEN (-8030 3655);
DISPLAY INVISIBLE (-8030 3655);
FORCEADD OFFPAGE..4
R 2
(-8075 3850);
FORCEPROP 2 LAST $XR1 118 
J 0
(-8477 3850);
DISPLAY 0.638298 (-8477 3850);
PAINT MONO (-8477 3850);
FORCEPROP 2 LAST $XR0 117 
J 0
(-8357 3850);
DISPLAY 0.638298 (-8357 3850);
PAINT MONO (-8357 3850);
FORCEPROP 2 LAST CDS_LIB standard
J 0
(-8075 3850);
DISPLAY INVISIBLE (-8075 3850);
FORCEPROP 2 LAST PATH I1336
J 0
(-8025 3925);
DISPLAY 0.680851 (-8025 3925);
DISPLAY INVISIBLE (-8025 3925);
FORCEPROP 1 LAST COMMENT_BODY TRUE
J 2
(-8050 3750);
DISPLAY 0.872340 (-8050 3750);
PAINT GREEN (-8050 3750);
DISPLAY INVISIBLE (-8050 3750);
FORCEPROP 1 LAST OFFPAGE TRUE
J 2
(-8400 3725);
DISPLAY 0.872340 (-8400 3725);
PAINT GREEN (-8400 3725);
DISPLAY INVISIBLE (-8400 3725);
FORCEADD OFFPAGE..2
R 2
(-8075 3650);
FORCEPROP 2 LAST $XR1 115 
J 0
(-8480 3650);
DISPLAY 0.638298 (-8480 3650);
PAINT MONO (-8480 3650);
FORCEPROP 2 LAST $XR0 133 
J 0
(-8360 3650);
DISPLAY 0.638298 (-8360 3650);
PAINT MONO (-8360 3650);
FORCEPROP 2 LAST PATH I1337
J 0
(-8025 3725);
DISPLAY 0.680851 (-8025 3725);
DISPLAY INVISIBLE (-8025 3725);
FORCEPROP 1 LAST COMMENT_BODY TRUE
J 2
(-8030 3555);
DISPLAY 0.872340 (-8030 3555);
PAINT GREEN (-8030 3555);
DISPLAY INVISIBLE (-8030 3555);
FORCEPROP 1 LAST OFFPAGE TRUE
J 2
(-8400 3525);
DISPLAY 0.872340 (-8400 3525);
PAINT GREEN (-8400 3525);
DISPLAY INVISIBLE (-8400 3525);
FORCEPROP 2 LAST CDS_LIB standard
J 0
(-8075 3650);
DISPLAY INVISIBLE (-8075 3650);
FORCEADD OFFPAGE..2
R 2
(-8075 3600);
FORCEPROP 2 LAST $XR1 115 
J 0
(-8480 3600);
DISPLAY 0.638298 (-8480 3600);
PAINT MONO (-8480 3600);
FORCEPROP 2 LAST $XR0 133 
J 0
(-8360 3600);
DISPLAY 0.638298 (-8360 3600);
PAINT MONO (-8360 3600);
FORCEPROP 2 LAST PATH I1338
J 0
(-8025 3675);
DISPLAY 0.680851 (-8025 3675);
DISPLAY INVISIBLE (-8025 3675);
FORCEPROP 1 LAST COMMENT_BODY TRUE
J 2
(-8030 3505);
DISPLAY 0.872340 (-8030 3505);
PAINT GREEN (-8030 3505);
DISPLAY INVISIBLE (-8030 3505);
FORCEPROP 1 LAST OFFPAGE TRUE
J 2
(-8400 3475);
DISPLAY 0.872340 (-8400 3475);
PAINT GREEN (-8400 3475);
DISPLAY INVISIBLE (-8400 3475);
FORCEPROP 2 LAST CDS_LIB standard
J 0
(-8075 3600);
DISPLAY INVISIBLE (-8075 3600);
FORCEADD OFFPAGE..2
R 2
(-8075 3550);
FORCEPROP 2 LAST $XR1 116 
J 0
(-8480 3550);
DISPLAY 0.638298 (-8480 3550);
PAINT MONO (-8480 3550);
FORCEPROP 2 LAST $XR0 133 
J 0
(-8360 3550);
DISPLAY 0.638298 (-8360 3550);
PAINT MONO (-8360 3550);
FORCEPROP 2 LAST PATH I1339
J 0
(-8025 3625);
DISPLAY 0.680851 (-8025 3625);
DISPLAY INVISIBLE (-8025 3625);
FORCEPROP 1 LAST OFFPAGE TRUE
J 2
(-8400 3425);
DISPLAY 0.872340 (-8400 3425);
PAINT GREEN (-8400 3425);
DISPLAY INVISIBLE (-8400 3425);
FORCEPROP 1 LAST COMMENT_BODY TRUE
J 2
(-8030 3455);
DISPLAY 0.872340 (-8030 3455);
PAINT GREEN (-8030 3455);
DISPLAY INVISIBLE (-8030 3455);
FORCEPROP 2 LAST CDS_LIB standard
J 0
(-8075 3550);
DISPLAY INVISIBLE (-8075 3550);
FORCEADD OFFPAGE..2
R 2
(-8075 3400);
FORCEPROP 2 LAST $XR1 209 
J 0
(-8449 3400);
DISPLAY 0.638298 (-8449 3400);
PAINT MONO (-8449 3400);
FORCEPROP 2 LAST $XR0 82 
J 0
(-8329 3400);
DISPLAY 0.638298 (-8329 3400);
PAINT MONO (-8329 3400);
FORCEPROP 2 LAST PATH I1340
J 0
(-8025 3475);
DISPLAY 0.680851 (-8025 3475);
DISPLAY INVISIBLE (-8025 3475);
FORCEPROP 1 LAST COMMENT_BODY TRUE
J 2
(-8030 3305);
DISPLAY 0.872340 (-8030 3305);
PAINT GREEN (-8030 3305);
DISPLAY INVISIBLE (-8030 3305);
FORCEPROP 1 LAST OFFPAGE TRUE
J 2
(-8400 3275);
DISPLAY 0.872340 (-8400 3275);
PAINT GREEN (-8400 3275);
DISPLAY INVISIBLE (-8400 3275);
FORCEPROP 2 LAST CDS_LIB standard
J 0
(-8075 3400);
DISPLAY INVISIBLE (-8075 3400);
FORCEADD OFFPAGE..4
R 2
(-8075 3350);
FORCEPROP 2 LAST $XR0 209 
J 0
(-8357 3350);
DISPLAY 0.638298 (-8357 3350);
PAINT MONO (-8357 3350);
FORCEPROP 2 LAST PATH I1341
J 0
(-8025 3425);
DISPLAY 0.680851 (-8025 3425);
DISPLAY INVISIBLE (-8025 3425);
FORCEPROP 1 LAST OFFPAGE TRUE
J 2
(-8400 3225);
DISPLAY 0.872340 (-8400 3225);
PAINT GREEN (-8400 3225);
DISPLAY INVISIBLE (-8400 3225);
FORCEPROP 1 LAST COMMENT_BODY TRUE
J 2
(-8050 3250);
DISPLAY 0.872340 (-8050 3250);
PAINT GREEN (-8050 3250);
DISPLAY INVISIBLE (-8050 3250);
FORCEPROP 2 LAST CDS_LIB standard
J 0
(-8075 3350);
DISPLAY INVISIBLE (-8075 3350);
FORCEADD OFFPAGE..2
R 2
(-8075 3300);
FORCEPROP 2 LAST $XR1 209 
J 0
(-8449 3300);
DISPLAY 0.638298 (-8449 3300);
PAINT MONO (-8449 3300);
FORCEPROP 2 LAST $XR0 82 
J 0
(-8329 3300);
DISPLAY 0.638298 (-8329 3300);
PAINT MONO (-8329 3300);
FORCEPROP 2 LAST PATH I1342
J 0
(-8025 3375);
DISPLAY 0.680851 (-8025 3375);
DISPLAY INVISIBLE (-8025 3375);
FORCEPROP 1 LAST COMMENT_BODY TRUE
J 2
(-8030 3205);
DISPLAY 0.872340 (-8030 3205);
PAINT GREEN (-8030 3205);
DISPLAY INVISIBLE (-8030 3205);
FORCEPROP 1 LAST OFFPAGE TRUE
J 2
(-8400 3175);
DISPLAY 0.872340 (-8400 3175);
PAINT GREEN (-8400 3175);
DISPLAY INVISIBLE (-8400 3175);
FORCEPROP 2 LAST CDS_LIB standard
J 0
(-8075 3300);
DISPLAY INVISIBLE (-8075 3300);
FORCEADD OFFPAGE..2
R 2
(-8075 3200);
FORCEPROP 2 LAST $XR0 125 
J 0
(-8360 3200);
DISPLAY 0.638298 (-8360 3200);
PAINT MONO (-8360 3200);
FORCEPROP 2 LAST PATH I1343
J 0
(-8025 3275);
DISPLAY 0.680851 (-8025 3275);
DISPLAY INVISIBLE (-8025 3275);
FORCEPROP 2 LAST CDS_LIB standard
J 0
(-8075 3200);
DISPLAY INVISIBLE (-8075 3200);
FORCEPROP 1 LAST COMMENT_BODY TRUE
J 2
(-8030 3105);
DISPLAY 0.872340 (-8030 3105);
PAINT GREEN (-8030 3105);
DISPLAY INVISIBLE (-8030 3105);
FORCEPROP 1 LAST OFFPAGE TRUE
J 2
(-8400 3075);
DISPLAY 0.872340 (-8400 3075);
PAINT GREEN (-8400 3075);
DISPLAY INVISIBLE (-8400 3075);
FORCEADD OFFPAGE..2
R 2
(-8075 3250);
FORCEPROP 2 LAST $XR1 114 
J 0
(-8480 3250);
DISPLAY 0.638298 (-8480 3250);
PAINT MONO (-8480 3250);
FORCEPROP 2 LAST $XR0 133 
J 0
(-8360 3250);
DISPLAY 0.638298 (-8360 3250);
PAINT MONO (-8360 3250);
FORCEPROP 2 LAST PATH I1344
J 0
(-8025 3325);
DISPLAY 0.680851 (-8025 3325);
DISPLAY INVISIBLE (-8025 3325);
FORCEPROP 2 LAST CDS_LIB standard
J 0
(-8075 3250);
DISPLAY INVISIBLE (-8075 3250);
FORCEPROP 1 LAST COMMENT_BODY TRUE
J 2
(-8030 3155);
DISPLAY 0.872340 (-8030 3155);
PAINT GREEN (-8030 3155);
DISPLAY INVISIBLE (-8030 3155);
FORCEPROP 1 LAST OFFPAGE TRUE
J 2
(-8400 3125);
DISPLAY 0.872340 (-8400 3125);
PAINT GREEN (-8400 3125);
DISPLAY INVISIBLE (-8400 3125);
FORCEADD Q_RES..1
R 2
(-7050 3000);
FORCEPROP 1 LAST LOCATION R70
J 0
(-7300 3000);
DISPLAY 0.489362 (-7300 3000);
PAINT SKYBLUE (-7300 3000);
FORCEPROP 0 LAST $SEC 1
J 0
(-7100 3050);
DISPLAY 0.680851 (-7100 3050);
PAINT MONO (-7100 3050);
DISPLAY INVISIBLE (-7100 3050);
FORCEPROP 0 LAST CDS_SEC 1
J 0
(-7100 3050);
DISPLAY 1.021277 (-7100 3050);
DISPLAY INVISIBLE (-7100 3050);
FORCEPROP 1 LASTPIN (-6950 3000) $PN 1
J 2
(-6962 3012);
DISPLAY 0.489362 (-6962 3012);
PAINT MONO (-6962 3012);
FORCEPROP 1 LASTPIN (-7150 3000) $PN 2
J 2
(-7135 3010);
DISPLAY 0.489362 (-7135 3010);
PAINT MONO (-7135 3010);
FORCEPROP 1 LAST VALUE 0
J 0
(-6925 3000);
DISPLAY 0.489362 (-6925 3000);
PAINT SKYBLUE (-6925 3000);
FORCEPROP 2 LAST BOM_COST MEM
J 0
(-7075 3150);
DISPLAY 0.744681 (-7075 3150);
PAINT WHITE (-7075 3150);
DISPLAY INVISIBLE (-7075 3150);
FORCEPROP 2 LAST CDS_LIB pure_quanta
J 0
(-7050 3000);
DISPLAY INVISIBLE (-7050 3000);
FORCEPROP 1 LAST PATH I1345
J 2
(-7000 3150);
DISPLAY 0.978723 (-7000 3150);
PAINT WHITE (-7000 3150);
DISPLAY INVISIBLE (-7000 3150);
FORCEPROP 1 LAST WATTAGE 1/16W
J 0
(-6975 2925);
DISPLAY 0.489362 (-6975 2925);
PAINT SKYBLUE (-6975 2925);
DISPLAY INVISIBLE (-6975 2925);
FORCEPROP 1 LAST MATERIAL CHIP
J 0
(-7225 2975);
DISPLAY 0.489362 (-7225 2975);
PAINT SKYBLUE (-7225 2975);
DISPLAY INVISIBLE (-7225 2975);
FORCEPROP 1 LAST TOLERANCE 5%
J 2
(-6925 2975);
DISPLAY 0.489362 (-6925 2975);
PAINT SKYBLUE (-6925 2975);
DISPLAY INVISIBLE (-6925 2975);
FORCEPROP 1 LAST PART_NUMBER CS00002JB38
J 0
(-7150 3050);
DISPLAY 0.489362 (-7150 3050);
PAINT SKYBLUE (-7150 3050);
DISPLAY INVISIBLE (-7150 3050);
FORCEPROP 1 LAST PACK_TYPE 0402LF
J 0
(-7225 2925);
DISPLAY 0.489362 (-7225 2925);
PAINT SKYBLUE (-7225 2925);
DISPLAY INVISIBLE (-7225 2925);
FORCEPROP 2 LAST ROOM RST_CPU0_PLD_TO_DIMM
J 0
(-7075 3100);
DISPLAY 0.744681 (-7075 3100);
PAINT RED (-7075 3100);
DISPLAY INVISIBLE (-7075 3100);
FORCEADD Q_RES..1
R 2
(-7050 2950);
FORCEPROP 1 LAST LOCATION R493
J 0
(-7300 2950);
DISPLAY 0.489362 (-7300 2950);
PAINT SKYBLUE (-7300 2950);
FORCEPROP 0 LAST $SEC 1
J 0
(-7100 3000);
DISPLAY 0.680851 (-7100 3000);
PAINT MONO (-7100 3000);
DISPLAY INVISIBLE (-7100 3000);
FORCEPROP 0 LAST CDS_SEC 1
J 0
(-7100 3000);
DISPLAY 1.021277 (-7100 3000);
DISPLAY INVISIBLE (-7100 3000);
FORCEPROP 1 LASTPIN (-6950 2950) $PN 1
J 2
(-6962 2962);
DISPLAY 0.489362 (-6962 2962);
PAINT MONO (-6962 2962);
FORCEPROP 1 LASTPIN (-7150 2950) $PN 2
J 2
(-7135 2960);
DISPLAY 0.489362 (-7135 2960);
PAINT MONO (-7135 2960);
FORCEPROP 1 LAST VALUE 0
J 0
(-6925 2950);
DISPLAY 0.489362 (-6925 2950);
PAINT SKYBLUE (-6925 2950);
FORCEPROP 2 LAST CDS_LIB pure_quanta
J 0
(-7050 2950);
DISPLAY INVISIBLE (-7050 2950);
FORCEPROP 2 LAST BOM_COST MEM
J 0
(-7075 3100);
DISPLAY 0.744681 (-7075 3100);
PAINT WHITE (-7075 3100);
DISPLAY INVISIBLE (-7075 3100);
FORCEPROP 1 LAST PATH I1346
J 2
(-7000 3100);
DISPLAY 0.978723 (-7000 3100);
PAINT WHITE (-7000 3100);
DISPLAY INVISIBLE (-7000 3100);
FORCEPROP 1 LAST WATTAGE 1/16W
J 0
(-6975 2875);
DISPLAY 0.489362 (-6975 2875);
PAINT SKYBLUE (-6975 2875);
DISPLAY INVISIBLE (-6975 2875);
FORCEPROP 1 LAST MATERIAL CHIP
J 0
(-7225 2925);
DISPLAY 0.489362 (-7225 2925);
PAINT SKYBLUE (-7225 2925);
DISPLAY INVISIBLE (-7225 2925);
FORCEPROP 1 LAST TOLERANCE 5%
J 2
(-6925 2925);
DISPLAY 0.489362 (-6925 2925);
PAINT SKYBLUE (-6925 2925);
DISPLAY INVISIBLE (-6925 2925);
FORCEPROP 1 LAST PART_NUMBER CS00002JB38
J 0
(-7150 3000);
DISPLAY 0.489362 (-7150 3000);
PAINT SKYBLUE (-7150 3000);
DISPLAY INVISIBLE (-7150 3000);
FORCEPROP 1 LAST PACK_TYPE 0402LF
J 0
(-7225 2875);
DISPLAY 0.489362 (-7225 2875);
PAINT SKYBLUE (-7225 2875);
DISPLAY INVISIBLE (-7225 2875);
FORCEPROP 2 LAST ROOM RST_CPU0_PLD_TO_DIMM
J 0
(-7075 3050);
DISPLAY 0.744681 (-7075 3050);
PAINT RED (-7075 3050);
DISPLAY INVISIBLE (-7075 3050);
FORCEADD Q_RES..1
R 2
(-7050 2750);
FORCEPROP 1 LAST LOCATION R992
J 0
(-7300 2750);
DISPLAY 0.489362 (-7300 2750);
PAINT SKYBLUE (-7300 2750);
FORCEPROP 0 LAST $SEC 1
J 0
(-7175 2800);
DISPLAY 0.680851 (-7175 2800);
PAINT MONO (-7175 2800);
DISPLAY INVISIBLE (-7175 2800);
FORCEPROP 0 LAST CDS_SEC 1
J 0
(-7175 2800);
DISPLAY 0.680851 (-7175 2800);
DISPLAY INVISIBLE (-7175 2800);
FORCEPROP 1 LASTPIN (-6950 2750) $PN 1
J 2
(-6962 2762);
DISPLAY 0.489362 (-6962 2762);
PAINT MONO (-6962 2762);
FORCEPROP 1 LASTPIN (-7150 2750) $PN 2
J 2
(-7112 2762);
DISPLAY 0.489362 (-7112 2762);
PAINT MONO (-7112 2762);
FORCEPROP 1 LAST VALUE 33
J 0
(-6925 2750);
DISPLAY 0.489362 (-6925 2750);
PAINT SKYBLUE (-6925 2750);
FORCEPROP 2 LAST BOM_COST MEM
J 0
(-7075 2900);
DISPLAY 0.744681 (-7075 2900);
PAINT WHITE (-7075 2900);
DISPLAY INVISIBLE (-7075 2900);
FORCEPROP 2 LAST CDS_LIB pure_quanta
J 0
(-7050 2750);
DISPLAY INVISIBLE (-7050 2750);
FORCEPROP 1 LAST PATH I1347
J 2
(-7000 2900);
DISPLAY 0.978723 (-7000 2900);
PAINT WHITE (-7000 2900);
DISPLAY INVISIBLE (-7000 2900);
FORCEPROP 1 LAST WATTAGE 1/16W
J 0
(-6975 2675);
DISPLAY 0.489362 (-6975 2675);
PAINT SKYBLUE (-6975 2675);
DISPLAY INVISIBLE (-6975 2675);
FORCEPROP 1 LAST MATERIAL CHIP
J 0
(-7225 2725);
DISPLAY 0.489362 (-7225 2725);
PAINT SKYBLUE (-7225 2725);
DISPLAY INVISIBLE (-7225 2725);
FORCEPROP 1 LAST TOLERANCE 5%
J 2
(-6925 2725);
DISPLAY 0.489362 (-6925 2725);
PAINT SKYBLUE (-6925 2725);
DISPLAY INVISIBLE (-6925 2725);
FORCEPROP 1 LAST PART_NUMBER CS03302JB29
J 0
(-7150 2800);
DISPLAY 0.489362 (-7150 2800);
PAINT SKYBLUE (-7150 2800);
DISPLAY INVISIBLE (-7150 2800);
FORCEPROP 1 LAST PACK_TYPE 0402LF
J 0
(-7225 2675);
DISPLAY 0.489362 (-7225 2675);
PAINT SKYBLUE (-7225 2675);
DISPLAY INVISIBLE (-7225 2675);
FORCEPROP 2 LAST ROOM RST_CPU0_PLD_TO_DIMM
J 0
(-7075 2850);
DISPLAY 0.744681 (-7075 2850);
PAINT RED (-7075 2850);
DISPLAY INVISIBLE (-7075 2850);
FORCEADD Q_RES..1
R 2
(-7050 2700);
FORCEPROP 1 LAST LOCATION R160
J 0
(-7300 2700);
DISPLAY 0.489362 (-7300 2700);
PAINT SKYBLUE (-7300 2700);
FORCEPROP 0 LAST $SEC 1
J 0
(-7175 2750);
DISPLAY 0.680851 (-7175 2750);
PAINT MONO (-7175 2750);
DISPLAY INVISIBLE (-7175 2750);
FORCEPROP 0 LAST CDS_SEC 1
J 0
(-7175 2750);
DISPLAY 1.021277 (-7175 2750);
DISPLAY INVISIBLE (-7175 2750);
FORCEPROP 1 LASTPIN (-6950 2700) $PN 1
J 2
(-6962 2712);
DISPLAY 0.489362 (-6962 2712);
PAINT MONO (-6962 2712);
FORCEPROP 1 LASTPIN (-7150 2700) $PN 2
J 2
(-7112 2712);
DISPLAY 0.489362 (-7112 2712);
PAINT MONO (-7112 2712);
FORCEPROP 1 LAST VALUE 33
J 0
(-6925 2700);
DISPLAY 0.489362 (-6925 2700);
PAINT SKYBLUE (-6925 2700);
FORCEPROP 2 LAST CDS_LIB pure_quanta
J 0
(-7050 2700);
DISPLAY INVISIBLE (-7050 2700);
FORCEPROP 2 LAST BOM_COST MEM
J 0
(-7075 2850);
DISPLAY 0.744681 (-7075 2850);
PAINT WHITE (-7075 2850);
DISPLAY INVISIBLE (-7075 2850);
FORCEPROP 1 LAST PATH I1348
J 2
(-7000 2850);
DISPLAY 0.978723 (-7000 2850);
PAINT WHITE (-7000 2850);
DISPLAY INVISIBLE (-7000 2850);
FORCEPROP 1 LAST WATTAGE 1/16W
J 0
(-6975 2625);
DISPLAY 0.489362 (-6975 2625);
PAINT SKYBLUE (-6975 2625);
DISPLAY INVISIBLE (-6975 2625);
FORCEPROP 1 LAST MATERIAL CHIP
J 0
(-7225 2675);
DISPLAY 0.489362 (-7225 2675);
PAINT SKYBLUE (-7225 2675);
DISPLAY INVISIBLE (-7225 2675);
FORCEPROP 1 LAST TOLERANCE 5%
J 2
(-6925 2675);
DISPLAY 0.489362 (-6925 2675);
PAINT SKYBLUE (-6925 2675);
DISPLAY INVISIBLE (-6925 2675);
FORCEPROP 1 LAST PART_NUMBER CS03302JB29
J 0
(-7150 2750);
DISPLAY 0.489362 (-7150 2750);
PAINT SKYBLUE (-7150 2750);
DISPLAY INVISIBLE (-7150 2750);
FORCEPROP 1 LAST PACK_TYPE 0402LF
J 0
(-7225 2625);
DISPLAY 0.489362 (-7225 2625);
PAINT SKYBLUE (-7225 2625);
DISPLAY INVISIBLE (-7225 2625);
FORCEPROP 2 LAST ROOM RST_CPU0_PLD_TO_DIMM
J 0
(-7075 2800);
DISPLAY 0.744681 (-7075 2800);
PAINT RED (-7075 2800);
DISPLAY INVISIBLE (-7075 2800);
FORCEADD OFFPAGE..2
R 2
(-8075 3150);
FORCEPROP 2 LAST $XR0 124 
J 0
(-8360 3150);
DISPLAY 0.638298 (-8360 3150);
PAINT MONO (-8360 3150);
FORCEPROP 2 LAST PATH I1349
J 0
(-8025 3225);
DISPLAY 0.680851 (-8025 3225);
DISPLAY INVISIBLE (-8025 3225);
FORCEPROP 1 LAST OFFPAGE TRUE
J 2
(-8400 3025);
DISPLAY 0.872340 (-8400 3025);
PAINT GREEN (-8400 3025);
DISPLAY INVISIBLE (-8400 3025);
FORCEPROP 1 LAST COMMENT_BODY TRUE
J 2
(-8030 3055);
DISPLAY 0.872340 (-8030 3055);
PAINT GREEN (-8030 3055);
DISPLAY INVISIBLE (-8030 3055);
FORCEPROP 2 LAST CDS_LIB standard
J 0
(-8075 3150);
DISPLAY INVISIBLE (-8075 3150);
FORCEADD OFFPAGE..4
R 2
(-8075 3100);
FORCEPROP 2 LAST $XR0 164 
J 0
(-8357 3100);
DISPLAY 0.638298 (-8357 3100);
PAINT MONO (-8357 3100);
FORCEPROP 2 LAST PATH I1350
J 0
(-8025 3175);
DISPLAY 0.680851 (-8025 3175);
DISPLAY INVISIBLE (-8025 3175);
FORCEPROP 2 LAST CDS_LIB standard
J 0
(-8075 3100);
DISPLAY INVISIBLE (-8075 3100);
FORCEPROP 1 LAST OFFPAGE TRUE
J 2
(-8400 2975);
DISPLAY 0.872340 (-8400 2975);
PAINT GREEN (-8400 2975);
DISPLAY INVISIBLE (-8400 2975);
FORCEPROP 1 LAST COMMENT_BODY TRUE
J 2
(-8050 3000);
DISPLAY 0.872340 (-8050 3000);
PAINT GREEN (-8050 3000);
DISPLAY INVISIBLE (-8050 3000);
FORCEADD OFFPAGE..4
R 2
(-8075 3000);
FORCEPROP 2 LAST $XR0 34 
J 0
(-8296 3000);
DISPLAY 0.638298 (-8296 3000);
PAINT MONO (-8296 3000);
FORCEPROP 2 LAST PATH I1351
J 0
(-8025 3075);
DISPLAY 0.680851 (-8025 3075);
DISPLAY INVISIBLE (-8025 3075);
FORCEPROP 2 LAST CDS_LIB standard
J 0
(-8075 3000);
DISPLAY INVISIBLE (-8075 3000);
FORCEPROP 1 LAST OFFPAGE TRUE
J 2
(-8400 2875);
DISPLAY 0.872340 (-8400 2875);
PAINT GREEN (-8400 2875);
DISPLAY INVISIBLE (-8400 2875);
FORCEPROP 1 LAST COMMENT_BODY TRUE
J 2
(-8050 2900);
DISPLAY 0.872340 (-8050 2900);
PAINT GREEN (-8050 2900);
DISPLAY INVISIBLE (-8050 2900);
FORCEADD OFFPAGE..4
R 2
(-8075 3050);
FORCEPROP 2 LAST $XR0 164 
J 0
(-8327 3050);
DISPLAY 0.638298 (-8327 3050);
PAINT MONO (-8327 3050);
FORCEPROP 2 LAST PATH I1352
J 0
(-8025 3125);
DISPLAY 0.680851 (-8025 3125);
DISPLAY INVISIBLE (-8025 3125);
FORCEPROP 2 LAST CDS_LIB standard
J 0
(-8075 3050);
DISPLAY INVISIBLE (-8075 3050);
FORCEPROP 1 LAST OFFPAGE TRUE
J 2
(-8400 2925);
DISPLAY 0.872340 (-8400 2925);
PAINT GREEN (-8400 2925);
DISPLAY INVISIBLE (-8400 2925);
FORCEPROP 1 LAST COMMENT_BODY TRUE
J 2
(-8050 2950);
DISPLAY 0.872340 (-8050 2950);
PAINT GREEN (-8050 2950);
DISPLAY INVISIBLE (-8050 2950);
FORCEADD OFFPAGE..3
R 2
(-8075 2950);
FORCEPROP 2 LAST $XR0 34 
J 0
(-8324 2950);
DISPLAY 0.638298 (-8324 2950);
PAINT MONO (-8324 2950);
FORCEPROP 2 LAST PATH I1353
J 0
(-8025 3025);
DISPLAY 0.680851 (-8025 3025);
DISPLAY INVISIBLE (-8025 3025);
FORCEPROP 2 LAST CDS_LIB standard
J 0
(-8075 2950);
DISPLAY INVISIBLE (-8075 2950);
FORCEPROP 1 LAST OFFPAGE TRUE
J 2
(-8400 2825);
DISPLAY 0.872340 (-8400 2825);
PAINT GREEN (-8400 2825);
DISPLAY INVISIBLE (-8400 2825);
FORCEPROP 1 LAST COMMENT_BODY TRUE
J 2
(-8025 2850);
DISPLAY 0.872340 (-8025 2850);
PAINT GREEN (-8025 2850);
DISPLAY INVISIBLE (-8025 2850);
FORCEADD OFFPAGE..2
R 2
(-8075 2750);
FORCEPROP 2 LAST $XR1 133 
J 0
(-8449 2750);
DISPLAY 0.638298 (-8449 2750);
PAINT MONO (-8449 2750);
FORCEPROP 2 LAST $XR0 82 
J 0
(-8329 2750);
DISPLAY 0.638298 (-8329 2750);
PAINT MONO (-8329 2750);
FORCEPROP 2 LAST CDS_LIB standard
J 0
(-8075 2750);
DISPLAY INVISIBLE (-8075 2750);
FORCEPROP 1 LAST OFFPAGE TRUE
J 2
(-8400 2625);
DISPLAY 0.872340 (-8400 2625);
PAINT GREEN (-8400 2625);
DISPLAY INVISIBLE (-8400 2625);
FORCEPROP 1 LAST COMMENT_BODY TRUE
J 2
(-8030 2655);
DISPLAY 0.872340 (-8030 2655);
PAINT GREEN (-8030 2655);
DISPLAY INVISIBLE (-8030 2655);
FORCEPROP 2 LAST PATH I1354
J 0
(-8025 2825);
DISPLAY 0.680851 (-8025 2825);
DISPLAY INVISIBLE (-8025 2825);
FORCEADD OFFPAGE..2
R 2
(-8075 2850);
FORCEPROP 2 LAST $XR0 126 
J 0
(-8360 2850);
DISPLAY 0.638298 (-8360 2850);
PAINT MONO (-8360 2850);
FORCEPROP 2 LAST PATH I1355
J 0
(-8025 2925);
DISPLAY 0.680851 (-8025 2925);
DISPLAY INVISIBLE (-8025 2925);
FORCEPROP 2 LAST CDS_LIB standard
J 0
(-8075 2850);
DISPLAY INVISIBLE (-8075 2850);
FORCEPROP 1 LAST COMMENT_BODY TRUE
J 2
(-8030 2755);
DISPLAY 0.872340 (-8030 2755);
PAINT GREEN (-8030 2755);
DISPLAY INVISIBLE (-8030 2755);
FORCEPROP 1 LAST OFFPAGE TRUE
J 2
(-8400 2725);
DISPLAY 0.872340 (-8400 2725);
PAINT GREEN (-8400 2725);
DISPLAY INVISIBLE (-8400 2725);
FORCEADD OFFPAGE..2
R 2
(-8075 2800);
FORCEPROP 2 LAST $XR0 127 
J 0
(-8360 2800);
DISPLAY 0.638298 (-8360 2800);
PAINT MONO (-8360 2800);
FORCEPROP 2 LAST PATH I1356
J 0
(-8025 2875);
DISPLAY 0.680851 (-8025 2875);
DISPLAY INVISIBLE (-8025 2875);
FORCEPROP 2 LAST CDS_LIB standard
J 0
(-8075 2800);
DISPLAY INVISIBLE (-8075 2800);
FORCEPROP 1 LAST COMMENT_BODY TRUE
J 2
(-8030 2705);
DISPLAY 0.872340 (-8030 2705);
PAINT GREEN (-8030 2705);
DISPLAY INVISIBLE (-8030 2705);
FORCEPROP 1 LAST OFFPAGE TRUE
J 2
(-8400 2675);
DISPLAY 0.872340 (-8400 2675);
PAINT GREEN (-8400 2675);
DISPLAY INVISIBLE (-8400 2675);
FORCEADD OFFPAGE..2
R 2
(-8075 2700);
FORCEPROP 2 LAST $XR0 149 
J 0
(-8360 2700);
DISPLAY 0.638298 (-8360 2700);
PAINT MONO (-8360 2700);
FORCEPROP 2 LAST CDS_LIB standard
J 0
(-8075 2700);
DISPLAY INVISIBLE (-8075 2700);
FORCEPROP 1 LAST OFFPAGE TRUE
J 2
(-8400 2575);
DISPLAY 0.872340 (-8400 2575);
PAINT GREEN (-8400 2575);
DISPLAY INVISIBLE (-8400 2575);
FORCEPROP 1 LAST COMMENT_BODY TRUE
J 2
(-8030 2605);
DISPLAY 0.872340 (-8030 2605);
PAINT GREEN (-8030 2605);
DISPLAY INVISIBLE (-8030 2605);
FORCEPROP 2 LAST PATH I1357
J 0
(-8025 2775);
DISPLAY 0.680851 (-8025 2775);
DISPLAY INVISIBLE (-8025 2775);
FORCEADD OFFPAGE..1
R 2
(-1975 2950);
FORCEPROP 2 LAST $XR0 162 
J 0
(-1789 2950);
DISPLAY 0.638298 (-1789 2950);
PAINT MONO (-1789 2950);
FORCEPROP 1 LAST OFFPAGE TRUE
J 2
(-2300 2825);
DISPLAY 0.872340 (-2300 2825);
PAINT GREEN (-2300 2825);
DISPLAY INVISIBLE (-2300 2825);
FORCEPROP 1 LAST COMMENT_BODY TRUE
J 2
(-2100 2850);
DISPLAY 0.872340 (-2100 2850);
PAINT GREEN (-2100 2850);
DISPLAY INVISIBLE (-2100 2850);
FORCEPROP 2 LAST PATH I1358
J 0
(-1800 3025);
DISPLAY 0.680851 (-1800 3025);
DISPLAY INVISIBLE (-1800 3025);
FORCEPROP 2 LAST CDS_LIB standard
J 0
(-1975 2950);
DISPLAY INVISIBLE (-1975 2950);
FORCEADD OFFPAGE..4
R 2
(-8075 4500);
FORCEPROP 2 LAST $XR1 165 
J 0
(-8477 4500);
DISPLAY 0.638298 (-8477 4500);
PAINT MONO (-8477 4500);
FORCEPROP 2 LAST $XR0 162 
J 0
(-8357 4500);
DISPLAY 0.638298 (-8357 4500);
PAINT MONO (-8357 4500);
FORCEPROP 2 LAST CDS_LIB standard
J 0
(-8075 4500);
DISPLAY INVISIBLE (-8075 4500);
FORCEPROP 2 LAST PATH I1359
J 0
(-8025 4575);
DISPLAY 0.680851 (-8025 4575);
DISPLAY INVISIBLE (-8025 4575);
FORCEPROP 1 LAST OFFPAGE TRUE
J 2
(-8400 4375);
DISPLAY 0.872340 (-8400 4375);
PAINT GREEN (-8400 4375);
DISPLAY INVISIBLE (-8400 4375);
FORCEPROP 1 LAST COMMENT_BODY TRUE
J 2
(-8050 4400);
DISPLAY 0.872340 (-8050 4400);
PAINT GREEN (-8050 4400);
DISPLAY INVISIBLE (-8050 4400);
FORCEADD Q_RES..1
R 2
(-7050 3800);
FORCEPROP 1 LAST $LOCATION R1548
J 0
(-7275 3800);
DISPLAY 0.489362 (-7275 3800);
PAINT SKYBLUE (-7275 3800);
FORCEPROP 0 LAST CDS_LOCATION R1548
J 0
(-6925 3825);
DISPLAY 0.680851 (-6925 3825);
DISPLAY INVISIBLE (-6925 3825);
FORCEPROP 0 LAST $SEC 1
J 0
(-6925 3825);
DISPLAY 0.680851 (-6925 3825);
PAINT MONO (-6925 3825);
DISPLAY INVISIBLE (-6925 3825);
FORCEPROP 0 LAST CDS_SEC 1
J 0
(-6925 3825);
DISPLAY 0.680851 (-6925 3825);
DISPLAY INVISIBLE (-6925 3825);
FORCEPROP 1 LASTPIN (-6950 3800) $PN 1
J 2
(-6962 3812);
DISPLAY 0.787234 (-6962 3812);
PAINT MONO (-6962 3812);
FORCEPROP 1 LASTPIN (-7150 3800) $PN 2
J 2
(-7112 3812);
DISPLAY 0.787234 (-7112 3812);
PAINT MONO (-7112 3812);
FORCEPROP 1 LAST VALUE 33
J 0
(-6925 3800);
DISPLAY 0.489362 (-6925 3800);
PAINT SKYBLUE (-6925 3800);
FORCEPROP 2 LAST BOM_COST MEM
J 0
(-7075 3950);
DISPLAY 0.744681 (-7075 3950);
PAINT WHITE (-7075 3950);
DISPLAY INVISIBLE (-7075 3950);
FORCEPROP 1 LAST WATTAGE 1/16W
J 0
(-6975 3725);
DISPLAY 0.489362 (-6975 3725);
PAINT SKYBLUE (-6975 3725);
DISPLAY INVISIBLE (-6975 3725);
FORCEPROP 1 LAST MATERIAL CHIP
J 0
(-7225 3775);
DISPLAY 0.489362 (-7225 3775);
PAINT SKYBLUE (-7225 3775);
DISPLAY INVISIBLE (-7225 3775);
FORCEPROP 1 LAST TOLERANCE 5%
J 2
(-6925 3775);
DISPLAY 0.489362 (-6925 3775);
PAINT SKYBLUE (-6925 3775);
DISPLAY INVISIBLE (-6925 3775);
FORCEPROP 1 LAST PART_NUMBER CS03302JB29
J 0
(-7150 3850);
DISPLAY 0.489362 (-7150 3850);
PAINT SKYBLUE (-7150 3850);
DISPLAY INVISIBLE (-7150 3850);
FORCEPROP 1 LAST PACK_TYPE 0402LF
J 0
(-7225 3725);
DISPLAY 0.489362 (-7225 3725);
PAINT SKYBLUE (-7225 3725);
DISPLAY INVISIBLE (-7225 3725);
FORCEPROP 2 LAST ROOM RST_CPU0_PLD_TO_DIMM
J 0
(-7075 3900);
DISPLAY 0.744681 (-7075 3900);
PAINT RED (-7075 3900);
DISPLAY INVISIBLE (-7075 3900);
FORCEPROP 1 LAST PATH I1362
J 2
(-7000 3950);
DISPLAY 0.978723 (-7000 3950);
PAINT WHITE (-7000 3950);
DISPLAY INVISIBLE (-7000 3950);
FORCEPROP 2 LAST CDS_LIB pure_quanta
J 0
(-7050 3800);
DISPLAY INVISIBLE (-7050 3800);
FORCEADD OFFPAGE..4
R 2
(-8075 3800);
FORCEPROP 2 LAST $XR1 165 
J 0
(-8447 3800);
DISPLAY 0.638298 (-8447 3800);
PAINT MONO (-8447 3800);
FORCEPROP 2 LAST $XR0 117 
J 0
(-8327 3800);
DISPLAY 0.638298 (-8327 3800);
PAINT MONO (-8327 3800);
FORCEPROP 1 LAST OFFPAGE TRUE
J 2
(-8400 3675);
DISPLAY 0.872340 (-8400 3675);
PAINT GREEN (-8400 3675);
DISPLAY INVISIBLE (-8400 3675);
FORCEPROP 1 LAST COMMENT_BODY TRUE
J 2
(-8050 3700);
DISPLAY 0.872340 (-8050 3700);
PAINT GREEN (-8050 3700);
DISPLAY INVISIBLE (-8050 3700);
FORCEPROP 2 LAST PATH I1363
J 0
(-8025 3875);
DISPLAY 0.680851 (-8025 3875);
DISPLAY INVISIBLE (-8025 3875);
FORCEPROP 2 LAST CDS_LIB standard
J 0
(-8075 3800);
DISPLAY INVISIBLE (-8075 3800);
FORCEADD QUANTA_TITLE_BLOCK_C..1
(0 0);
FORCEPROP 0 LAST CDS_CON_LAST_MODIFIED Fri Mar 11 14:53:19 2022
J 0
(-1885 15);
DISPLAY INVISIBLE (-1885 15);
FORCEPROP 1 LAST CUSTOM_TXT_CDS <CON_LAST_MODIFIED>
J 0
(-1885 15);
DISPLAY 0.978723 (-1885 15);
FORCEPROP 2 LAST CUSTOM_TXT_CDS <XR_PAGE_TITLE>
J 0
(-7890 5250);
DISPLAY 0.638298 (-7890 5250);
PAINT PINK (-7890 5250);
DISPLAY INVISIBLE (-7890 5250);
FORCEPROP 1 LAST CUSTOM_TXT_CDS <NAME_2>
J 0
(-3175 50);
FORCEPROP 1 LAST CUSTOM_TXT_CDS <NAME_1>
J 0
(-3175 175);
FORCEPROP 1 LAST CUSTOM_TXT_CDS <Q_NUMBER>
J 0
(-1403 103);
DISPLAY 1.212766 (-1403 103);
FORCEPROP 1 LAST CUSTOM_TXT_CDS <Q_PROJ>
J 0
(-2382 102);
DISPLAY 1.212766 (-2382 102);
FORCEPROP 1 LAST CUSTOM_TXT_CDS <Q_REV>
J 0
(-184 103);
DISPLAY 1.212766 (-184 103);
FORCEPROP 1 LAST CUSTOM_TXT_CDS <CON_PAGE_NUM> OF <CON_TOTAL_PAGES>
J 0
(-446 18);
DISPLAY 0.978723 (-446 18);
FORCEPROP 1 LAST Q_TITLE FPGA 1/6
J 0
(-9300 50);
DISPLAY 2.446809 (-9300 50);
PAINT GREEN (-9300 50);
FORCEPROP 1 LAST Q_DEPT BU9
J 1
(-3763 49);
DISPLAY 1.957447 (-3763 49);
PAINT GREEN (-3763 49);
FORCEPROP 1 LAST CDS_LMAN_SYM_OUTLINE -9475,6775,100,-125
J 0
(0 0);
DISPLAY 0.468085 (0 0);
PAINT GREEN (0 0);
DISPLAY INVISIBLE (0 0);
FORCEPROP 2 LAST CDS_LIB pure_quanta
J 0
(0 0);
DISPLAY INVISIBLE (0 0);
FORCEPROP 2 LAST PAGE_BORDER TRUE
J 0
(-7890 5250);
DISPLAY 0.638298 (-7890 5250);
PAINT PINK (-7890 5250);
DISPLAY INVISIBLE (-7890 5250);
FORCEPROP 1 LAST COMMENT_BODY TRUE
J 0
(12 -13);
DISPLAY 0.978723 (12 -13);
PAINT GREEN (12 -13);
DISPLAY INVISIBLE (12 -13);
FORCEPROP 2 LAST CDS_XR_PAGE_TITLE CR-79 : @T6G_MB_LIB.T6G(SCH_1):PAGE79
J 0
(-7890 5250);
DISPLAY 0.638298 (-7890 5250);
PAINT PINK (-7890 5250);
DISPLAY INVISIBLE (-7890 5250);
FORCEADD DNS..2
(-7175 3625);
PAINT RED (-7175 3625);
FORCEPROP 2 LAST CDS_LIB mstr_misc
J 0
(-7175 3625);
DISPLAY INVISIBLE (-7175 3625);
FORCEPROP 1 LAST COMMENT_BODY TRUE
R 1
J 0
(-7100 3400);
DISPLAY 0.872340 (-7100 3400);
PAINT PEACH (-7100 3400);
DISPLAY INVISIBLE (-7100 3400);
FORCEADD DNS..2
(-7175 3750);
PAINT RED (-7175 3750);
FORCEPROP 2 LAST CDS_LIB mstr_misc
J 0
(-7175 3750);
DISPLAY INVISIBLE (-7175 3750);
FORCEPROP 1 LAST COMMENT_BODY TRUE
R 1
J 0
(-7100 3525);
DISPLAY 0.872340 (-7100 3525);
PAINT PEACH (-7100 3525);
DISPLAY INVISIBLE (-7100 3525);
FORCEADD DNS..2
(-7175 3250);
PAINT RED (-7175 3250);
FORCEPROP 2 LAST CDS_LIB mstr_misc
J 0
(-7175 3250);
DISPLAY INVISIBLE (-7175 3250);
FORCEPROP 1 LAST COMMENT_BODY TRUE
R 1
J 0
(-7100 3025);
DISPLAY 0.872340 (-7100 3025);
PAINT PEACH (-7100 3025);
DISPLAY INVISIBLE (-7100 3025);
WIRE 16 -1 (-3975 3150)(-3075 3150);
FORCEPROP 2 LAST SIG_NAME FM_CLK_100M_SLOT2_0_OE_R_N
J 0
(-3875 3160);
DISPLAY 0.489362 (-3875 3160);
FORCEPROP 2 LASTPROP $XRERR UNIQUE?
J 0
(-4115 3160);
DISPLAY 0.638298 (-4115 3160);
PAINT MONO (-4115 3160);
DISPLAY INVISIBLE (-4115 3160);
WIRE 16 -1 (-3975 3100)(-2025 3100);
FORCEPROP 2 LAST SIG_NAME SCM_SPARE_0
J 0
(-3875 3110);
DISPLAY 0.489362 (-3875 3110);
WIRE 16 -1 (-2875 3250)(-2025 3250);
FORCEPROP 2 LAST SIG_NAME FM_CLK_100M_M2_1_OE_N
J 0
(-2750 3260);
DISPLAY 0.489362 (-2750 3260);
WIRE 16 -1 (-2875 3150)(-2025 3150);
FORCEPROP 2 LAST SIG_NAME FM_CLK_100M_SLOT2_0_OE_N
J 0
(-2750 3160);
DISPLAY 0.489362 (-2750 3160);
WIRE 16 -1 (-3975 3250)(-3075 3250);
FORCEPROP 2 LAST SIG_NAME FM_CLK_100M_M2_1_OE_R_N
J 0
(-3875 3260);
DISPLAY 0.489362 (-3875 3260);
FORCEPROP 2 LASTPROP $XRERR UNIQUE?
J 0
(-4115 3260);
DISPLAY 0.638298 (-4115 3260);
PAINT MONO (-4115 3260);
DISPLAY INVISIBLE (-4115 3260);
WIRE 16 -1 (-2875 3450)(-2025 3450);
FORCEPROP 2 LAST SIG_NAME FM_CLK_100M_SLOT3_OE_N
J 0
(-2750 3460);
DISPLAY 0.489362 (-2750 3460);
WIRE 16 -1 (-2875 3500)(-2025 3500);
FORCEPROP 2 LAST SIG_NAME FM_CLK_100M_SLOT1_0_OE_N
J 0
(-2750 3510);
DISPLAY 0.489362 (-2750 3510);
WIRE 16 -1 (-2025 3600)(-2875 3600);
FORCEPROP 0 LAST SIG_NAME FM_E1S_2_CLK_OE_R
J 0
(-2750 3610);
DISPLAY 0.489362 (-2750 3610);
WIRE 16 -1 (-2875 3650)(-2025 3650);
FORCEPROP 2 LAST SIG_NAME FM_CLK_100M_SLOT1_1_OE_N
J 0
(-2750 3660);
DISPLAY 0.489362 (-2750 3660);
WIRE 16 -1 (-3975 3000)(-3075 3000);
FORCEPROP 2 LAST SIG_NAME FM_CLK_100M_OCP_OE_R_N
J 0
(-3875 3010);
DISPLAY 0.489362 (-3875 3010);
FORCEPROP 2 LASTPROP $XRERR UNIQUE?
J 0
(-4115 3010);
DISPLAY 0.638298 (-4115 3010);
PAINT MONO (-4115 3010);
DISPLAY INVISIBLE (-4115 3010);
WIRE 16 -1 (-3975 2950)(-2025 2950);
FORCEPROP 2 LAST SIG_NAME IRQ_HSC_ALERT_N
J 0
(-2750 2960);
DISPLAY 0.489362 (-2750 2960);
WIRE 16 -1 (-2025 3700)(-3975 3700);
FORCEPROP 2 LAST SIG_NAME PWRGD_PVDDCR_SOC_P1
J 0
(-2750 3710);
DISPLAY 0.489362 (-2750 3710);
WIRE 16 -1 (-3975 3750)(-3075 3750);
FORCEPROP 2 LAST SIG_NAME FM_CLK_100M_SLOT2_1_OE_R_N
J 0
(-3875 3760);
DISPLAY 0.489362 (-3875 3760);
FORCEPROP 2 LASTPROP $XRERR UNIQUE?
J 0
(-4115 3760);
DISPLAY 0.638298 (-4115 3760);
PAINT MONO (-4115 3760);
DISPLAY INVISIBLE (-4115 3760);
WIRE 16 -1 (-3975 3800)(-3075 3800);
FORCEPROP 2 LAST SIG_NAME FM_CLK_100M_M2_2_OE_R_N
J 0
(-3875 3810);
DISPLAY 0.489362 (-3875 3810);
FORCEPROP 2 LASTPROP $XRERR UNIQUE?
J 0
(-4115 3810);
DISPLAY 0.638298 (-4115 3810);
PAINT MONO (-4115 3810);
DISPLAY INVISIBLE (-4115 3810);
WIRE 16 -1 (-2025 3850)(-3975 3850);
FORCEPROP 2 LAST SIG_NAME PVDDCR_CPU0_P0_EN
J 0
(-2750 3860);
DISPLAY 0.489362 (-2750 3860);
WIRE 16 -1 (-3975 3900)(-3075 3900);
FORCEPROP 0 LAST SIG_NAME FM_E1S_1_CLK_OE_N
J 0
(-3875 3910);
DISPLAY 0.489362 (-3875 3910);
FORCEPROP 2 LASTPROP $XRERR UNIQUE?
J 0
(-4115 3910);
DISPLAY 0.638298 (-4115 3910);
PAINT MONO (-4115 3910);
DISPLAY INVISIBLE (-4115 3910);
WIRE 16 -1 (-3975 3950)(-3075 3950);
FORCEPROP 2 LAST SIG_NAME FM_CLK_100M_SLOT1_3_OE_R_N
J 0
(-3875 3960);
DISPLAY 0.489362 (-3875 3960);
FORCEPROP 2 LASTPROP $XRERR UNIQUE?
J 0
(-4115 3960);
DISPLAY 0.638298 (-4115 3960);
PAINT MONO (-4115 3960);
DISPLAY INVISIBLE (-4115 3960);
WIRE 16 -1 (-2025 4000)(-3975 4000);
FORCEPROP 2 LAST SIG_NAME PVDDCR_SOC_P1_EN
J 0
(-2750 4010);
DISPLAY 0.489362 (-2750 4010);
WIRE 16 -1 (-3975 4050)(-2025 4050);
FORCEPROP 2 LAST SIG_NAME FPGA_RDY
J 0
(-3875 4060);
DISPLAY 0.489362 (-3875 4060);
WIRE 16 -1 (-3975 4100)(-3075 4100);
FORCEPROP 2 LAST SIG_NAME SCM_SYS_PWROK
J 0
(-3875 4110);
DISPLAY 0.489362 (-3875 4110);
FORCEPROP 2 LASTPROP $XRERR UNIQUE?
J 0
(-4115 4110);
DISPLAY 0.638298 (-4115 4110);
PAINT MONO (-4115 4110);
DISPLAY INVISIBLE (-4115 4110);
WIRE 16 -1 (-3975 3500)(-3075 3500);
FORCEPROP 2 LAST SIG_NAME FM_CLK_100M_SLOT1_0_OE_R_N
J 0
(-3875 3510);
DISPLAY 0.489362 (-3875 3510);
FORCEPROP 2 LASTPROP $XRERR UNIQUE?
J 0
(-4115 3510);
DISPLAY 0.638298 (-4115 3510);
PAINT MONO (-4115 3510);
DISPLAY INVISIBLE (-4115 3510);
WIRE 16 -1 (-3975 3600)(-3075 3600);
FORCEPROP 0 LAST SIG_NAME FM_E1S_2_CLK_OE_N
J 0
(-3875 3610);
DISPLAY 0.489362 (-3875 3610);
FORCEPROP 2 LASTPROP $XRERR UNIQUE?
J 0
(-4115 3610);
DISPLAY 0.638298 (-4115 3610);
PAINT MONO (-4115 3610);
DISPLAY INVISIBLE (-4115 3610);
WIRE 16 -1 (-3975 3650)(-3075 3650);
FORCEPROP 2 LAST SIG_NAME FM_CLK_100M_SLOT1_1_OE_R_N
J 0
(-3875 3660);
DISPLAY 0.489362 (-3875 3660);
FORCEPROP 2 LASTPROP $XRERR UNIQUE?
J 0
(-4115 3660);
DISPLAY 0.638298 (-4115 3660);
PAINT MONO (-4115 3660);
DISPLAY INVISIBLE (-4115 3660);
WIRE 16 -1 (-3975 3450)(-3075 3450);
FORCEPROP 2 LAST SIG_NAME FM_CLK_100M_SLOT3_OE_R_N
J 0
(-3875 3460);
DISPLAY 0.489362 (-3875 3460);
FORCEPROP 2 LASTPROP $XRERR UNIQUE?
J 0
(-4115 3460);
DISPLAY 0.638298 (-4115 3460);
PAINT MONO (-4115 3460);
DISPLAY INVISIBLE (-4115 3460);
WIRE 16 -1 (-2875 3000)(-2025 3000);
FORCEPROP 2 LAST SIG_NAME FM_CLK_100M_OCP_OE_N
J 0
(-2750 3010);
DISPLAY 0.489362 (-2750 3010);
WIRE 16 -1 (-3975 4200)(-3075 4200);
FORCEPROP 2 LAST SIG_NAME FM_CLK_100M_SLOT2_3_OE_R_N
J 0
(-3875 4210);
DISPLAY 0.489362 (-3875 4210);
FORCEPROP 2 LASTPROP $XRERR UNIQUE?
J 0
(-4115 4210);
DISPLAY 0.638298 (-4115 4210);
PAINT MONO (-4115 4210);
DISPLAY INVISIBLE (-4115 4210);
WIRE 16 -1 (-3075 4650)(-3975 4650);
FORCEPROP 2 LAST SIG_NAME SMB_SCM_1_R1_SCL
J 0
(-3875 4660);
DISPLAY 0.489362 (-3875 4660);
FORCEPROP 2 LASTPROP $XRERR UNIQUE?
J 0
(-4115 4660);
DISPLAY 0.638298 (-4115 4660);
PAINT MONO (-4115 4660);
DISPLAY INVISIBLE (-4115 4660);
WIRE 16 -1 (-2875 3750)(-2025 3750);
FORCEPROP 2 LAST SIG_NAME FM_CLK_100M_SLOT2_1_OE_N
J 0
(-2750 3760);
DISPLAY 0.489362 (-2750 3760);
WIRE 16 -1 (-6075 4000)(-6950 4000);
FORCEPROP 2 LAST SIG_NAME FM_P3V3_M2_1_EN
J 0
(-6850 4010);
DISPLAY 0.489362 (-6850 4010);
FORCEPROP 2 LASTPROP $XRERR UNIQUE?
J 0
(-7090 4010);
DISPLAY 0.638298 (-7090 4010);
PAINT MONO (-7090 4010);
DISPLAY INVISIBLE (-7090 4010);
WIRE 16 -1 (-6075 4050)(-8025 4050);
FORCEPROP 0 LAST $PNN SGPIO_SCM_DO_<0>
J 0
(-7925 4083);
DISPLAY INVISIBLE (-7925 4083);
FORCEPROP 2 LAST SIG_NAME SGPIO_SCM_DO_<0>
J 0
(-7875 4060);
DISPLAY 0.489362 (-7875 4060);
WIRE 16 -1 (-8025 4150)(-6075 4150);
FORCEPROP 2 LAST SIG_NAME PWGD_P3V3_M2_1_R
J 0
(-6850 4160);
DISPLAY 0.489362 (-6850 4160);
WIRE 16 -1 (-7150 4000)(-8025 4000);
FORCEPROP 2 LAST SIG_NAME P3V3_M2_1_EN
J 0
(-7875 4010);
DISPLAY 0.489362 (-7875 4010);
WIRE 16 -1 (-8025 3950)(-6075 3950);
FORCEPROP 2 LAST SIG_NAME PWGD_P3V3_M2_2_R
J 0
(-6850 3960);
DISPLAY 0.489362 (-6850 3960);
WIRE 16 -1 (-6075 3850)(-8025 3850);
FORCEPROP 0 LAST $PNN SGPIO_SCM_LD_<0>
J 0
(-7925 3883);
DISPLAY INVISIBLE (-7925 3883);
FORCEPROP 2 LAST SIG_NAME SGPIO_SCM_LD_<0>
J 0
(-7875 3860);
DISPLAY 0.489362 (-7875 3860);
WIRE 16 -1 (-7150 3800)(-8025 3800);
FORCEPROP 2 LAST SIG_NAME HPM_STBY_EN
J 0
(-7885 3810);
DISPLAY 0.446809 (-7885 3810);
WIRE 16 -1 (-7150 3750)(-8025 3750);
FORCEPROP 2 LAST SIG_NAME FM_SLOT1_PWRBRK1_N
J 0
(-7875 3760);
DISPLAY 0.489362 (-7875 3760);
WIRE 16 -1 (-7150 3700)(-8025 3700);
FORCEPROP 2 LAST SIG_NAME P3V3_M2_2_EN
J 0
(-7875 3710);
DISPLAY 0.489362 (-7875 3710);
WIRE 16 -1 (-7150 3600)(-8025 3600);
FORCEPROP 2 LAST SIG_NAME FM_SLOT2_PWRBRK1_N
J 0
(-7875 3610);
DISPLAY 0.489362 (-7875 3610);
WIRE 16 -1 (-8025 3400)(-7150 3400);
FORCEPROP 2 LAST SIG_NAME P3V3_OCP_EN_R
J 0
(-7875 3410);
DISPLAY 0.489362 (-7875 3410);
WIRE 16 -1 (-7150 3550)(-8025 3550);
FORCEPROP 2 LAST SIG_NAME FM_SLOT3_PWRBRK_N
J 0
(-7875 3560);
DISPLAY 0.489362 (-7875 3560);
WIRE 16 -1 (-8025 3650)(-7150 3650);
FORCEPROP 2 LAST SIG_NAME FM_SLOT2_PWRBRK0_N
J 0
(-7875 3660);
DISPLAY 0.489362 (-7875 3660);
WIRE 16 -1 (-6075 4200)(-8025 4200);
FORCEPROP 0 LAST $PNN SGPIO_SCM_LD_<1>
J 0
(-7925 4233);
DISPLAY INVISIBLE (-7925 4233);
FORCEPROP 2 LAST SIG_NAME SGPIO_SCM_LD_<1>
J 0
(-7875 4210);
DISPLAY 0.489362 (-7875 4210);
WIRE 16 -1 (-6075 4100)(-8025 4100);
FORCEPROP 2 LAST SIG_NAME SGPIO_SCM_CLK
J 0
(-7875 4110);
DISPLAY 0.489362 (-7875 4110);
WIRE 16 -1 (-7150 3900)(-8025 3900);
FORCEPROP 0 LAST $PNN SGPIO_SCM_DI_<1>
J 0
(-7875 3933);
DISPLAY INVISIBLE (-7875 3933);
FORCEPROP 2 LAST SIG_NAME SGPIO_SCM_DI_<1>
J 0
(-7875 3910);
DISPLAY 0.489362 (-7875 3910);
WIRE 16 -1 (-6950 3750)(-6075 3750);
FORCEPROP 0 LAST CDS_PHYS_NET_NAME FM_SLOT1_PWRBRK1_R_N
J 0
(-6675 3800);
PAINT MONO (-6675 3800);
DISPLAY INVISIBLE (-6675 3800);
FORCEPROP 2 LAST SIG_NAME FM_SLOT1_PWRBRK1_R_N
J 0
(-6850 3760);
DISPLAY 0.489362 (-6850 3760);
FORCEPROP 2 LASTPROP $XRERR UNIQUE?
J 0
(-7090 3760);
DISPLAY 0.638298 (-7090 3760);
PAINT MONO (-7090 3760);
DISPLAY INVISIBLE (-7090 3760);
WIRE 16 -1 (-6950 3900)(-6075 3900);
FORCEPROP 0 LAST $PNN SGPIO_SCM_DI_R<1>
J 0
(-6850 3933);
DISPLAY INVISIBLE (-6850 3933);
FORCEPROP 2 LAST SIG_NAME SGPIO_SCM_DI_R<1>
J 0
(-6850 3910);
DISPLAY 0.489362 (-6850 3910);
FORCEPROP 2 LASTPROP $XRERR UNIQUE?
J 0
(-7090 3910);
DISPLAY 0.638298 (-7090 3910);
PAINT MONO (-7090 3910);
DISPLAY INVISIBLE (-7090 3910);
WIRE 16 -1 (-6075 3800)(-6950 3800);
FORCEPROP 2 LAST SIG_NAME HPM_STBY_R_EN
J 0
(-6860 3810);
DISPLAY 0.446809 (-6860 3810);
FORCEPROP 2 LASTPROP $XRERR UNIQUE?
J 0
(-7100 3810);
DISPLAY 0.638298 (-7100 3810);
PAINT MONO (-7100 3810);
DISPLAY INVISIBLE (-7100 3810);
WIRE 16 -1 (-8025 4300)(-7150 4300);
FORCEPROP 2 LAST SIG_NAME FM_I3C_CPU1_MUX1_SEL
J 0
(-7875 4310);
DISPLAY 0.489362 (-7875 4310);
WIRE 16 -1 (-6950 4650)(-6075 4650);
FORCEPROP 2 LAST SIG_NAME FM_I3C_CPU0_MUX1_OE_R_N
J 0
(-6850 4660);
DISPLAY 0.489362 (-6850 4660);
FORCEPROP 2 LASTPROP $XRERR UNIQUE?
J 0
(-7090 4660);
DISPLAY 0.638298 (-7090 4660);
PAINT MONO (-7090 4660);
DISPLAY INVISIBLE (-7090 4660);
WIRE 16 -1 (-6075 4450)(-6950 4450);
FORCEPROP 2 LAST SIG_NAME SGPIO_SCM_INTR_R_N
J 0
(-6850 4460);
DISPLAY 0.489362 (-6850 4460);
FORCEPROP 2 LASTPROP $XRERR UNIQUE?
J 0
(-7090 4460);
DISPLAY 0.638298 (-7090 4460);
PAINT MONO (-7090 4460);
DISPLAY INVISIBLE (-7090 4460);
WIRE 16 -1 (-6075 4350)(-8025 4350);
FORCEPROP 2 LAST SIG_NAME SGPIO_SCM_RESET_N
J 0
(-7875 4360);
DISPLAY 0.489362 (-7875 4360);
WIRE 16 -1 (-6075 4400)(-8025 4400);
FORCEPROP 0 LAST $PNN SGPIO_SCM_DO_<1>
J 0
(-7925 4433);
DISPLAY INVISIBLE (-7925 4433);
FORCEPROP 2 LAST SIG_NAME SGPIO_SCM_DO_<1>
J 0
(-7875 4410);
DISPLAY 0.489362 (-7875 4410);
WIRE 16 -1 (-8025 4500)(-6075 4500);
FORCEPROP 2 LAST SIG_NAME PWRGD_P12V_STBY_R
J 0
(-7885 4510);
DISPLAY 0.446809 (-7885 4510);
WIRE 16 -1 (-6950 4600)(-6075 4600);
FORCEPROP 2 LAST SIG_NAME SCM_JTAG_MUX_R_S0
J 0
(-6850 4610);
DISPLAY 0.489362 (-6850 4610);
FORCEPROP 2 LASTPROP $XRERR UNIQUE?
J 0
(-7090 4610);
DISPLAY 0.638298 (-7090 4610);
PAINT MONO (-7090 4610);
DISPLAY INVISIBLE (-7090 4610);
WIRE 16 -1 (-6950 4700)(-6075 4700);
FORCEPROP 2 LAST SIG_NAME FM_I3C_CPU0_MUX0_R_SEL
J 0
(-6850 4710);
DISPLAY 0.489362 (-6850 4710);
FORCEPROP 2 LASTPROP $XRERR UNIQUE?
J 0
(-7090 4710);
DISPLAY 0.638298 (-7090 4710);
PAINT MONO (-7090 4710);
DISPLAY INVISIBLE (-7090 4710);
WIRE 16 -1 (-6950 4750)(-6075 4750);
FORCEPROP 2 LAST SIG_NAME SCM_JTAG_MUX_R_S1
J 0
(-6850 4760);
DISPLAY 0.489362 (-6850 4760);
FORCEPROP 2 LASTPROP $XRERR UNIQUE?
J 0
(-7090 4760);
DISPLAY 0.638298 (-7090 4760);
PAINT MONO (-7090 4760);
DISPLAY INVISIBLE (-7090 4760);
WIRE 16 -1 (-6950 4800)(-6075 4800);
FORCEPROP 2 LAST SIG_NAME FM_I3C_CPU1_MUX0_OE_R_N
J 0
(-6850 4810);
DISPLAY 0.489362 (-6850 4810);
FORCEPROP 2 LASTPROP $XRERR UNIQUE?
J 0
(-7090 4810);
DISPLAY 0.638298 (-7090 4810);
PAINT MONO (-7090 4810);
DISPLAY INVISIBLE (-7090 4810);
WIRE 16 -1 (-6950 5000)(-6075 5000);
FORCEPROP 2 LAST SIG_NAME FM_I3C_CPU0_MUX0_OE_R_N
J 0
(-6850 5010);
DISPLAY 0.489362 (-6850 5010);
FORCEPROP 2 LASTPROP $XRERR UNIQUE?
J 0
(-7090 5010);
DISPLAY 0.638298 (-7090 5010);
PAINT MONO (-7090 5010);
DISPLAY INVISIBLE (-7090 5010);
WIRE 16 -1 (-6075 3350)(-8025 3350);
FORCEPROP 2 LAST SIG_NAME PWGD_P3V3_OCP
J 0
(-7875 3360);
DISPLAY 0.489362 (-7875 3360);
WIRE 16 -1 (-7150 3300)(-8025 3300);
FORCEPROP 2 LAST SIG_NAME P12V_OCP_EN_R
J 0
(-7875 3310);
DISPLAY 0.489362 (-7875 3310);
WIRE 16 -1 (-6075 3200)(-8025 3200);
FORCEPROP 0 LAST SIG_NAME FM_LED_ACTIVE_E1S_2
J 0
(-7875 3210);
DISPLAY 0.489362 (-7875 3210);
WIRE 16 -1 (-6075 3150)(-8025 3150);
FORCEPROP 0 LAST SIG_NAME FM_LED_ACTIVE_E1S_1
J 0
(-7875 3160);
DISPLAY 0.489362 (-7875 3160);
WIRE 16 -1 (-8025 3100)(-6075 3100);
FORCEPROP 0 LAST SIG_NAME UV_ALERT_N
J 0
(-7925 3110);
DISPLAY 0.489362 (-7925 3110);
WIRE 16 -1 (-6950 3550)(-6075 3550);
FORCEPROP 0 LAST CDS_PHYS_NET_NAME FM_SLOT3_PWRBRK_R_N
J 0
(-6675 3600);
PAINT MONO (-6675 3600);
DISPLAY INVISIBLE (-6675 3600);
FORCEPROP 2 LAST SIG_NAME FM_SLOT3_PWRBRK_R_N
J 0
(-6850 3560);
DISPLAY 0.489362 (-6850 3560);
FORCEPROP 2 LASTPROP $XRERR UNIQUE?
J 0
(-7090 3560);
DISPLAY 0.638298 (-7090 3560);
PAINT MONO (-7090 3560);
DISPLAY INVISIBLE (-7090 3560);
WIRE 16 -1 (-8025 5000)(-7150 5000);
FORCEPROP 2 LAST SIG_NAME FM_I3C_CPU0_MUX0_OE_N
J 0
(-7875 5010);
DISPLAY 0.489362 (-7875 5010);
WIRE 16 -1 (-8025 4950)(-7150 4950);
FORCEPROP 2 LAST SIG_NAME FM_I3C_CPU1_MUX0_SEL
J 0
(-7875 4960);
DISPLAY 0.489362 (-7875 4960);
WIRE 16 -1 (-6950 4950)(-6075 4950);
FORCEPROP 2 LAST SIG_NAME FM_I3C_CPU1_MUX0_R_SEL
J 0
(-6850 4960);
DISPLAY 0.489362 (-6850 4960);
FORCEPROP 2 LASTPROP $XRERR UNIQUE?
J 0
(-7090 4960);
DISPLAY 0.638298 (-7090 4960);
PAINT MONO (-7090 4960);
DISPLAY INVISIBLE (-7090 4960);
WIRE 16 -1 (-6950 4900)(-6075 4900);
FORCEPROP 2 LAST SIG_NAME FM_I3C_CPU1_MUX1_OE_R_N
J 0
(-6850 4910);
DISPLAY 0.489362 (-6850 4910);
FORCEPROP 2 LASTPROP $XRERR UNIQUE?
J 0
(-7090 4910);
DISPLAY 0.638298 (-7090 4910);
PAINT MONO (-7090 4910);
DISPLAY INVISIBLE (-7090 4910);
WIRE 16 -1 (-3075 4900)(-3975 4900);
FORCEPROP 2 LAST SIG_NAME SMB_SCM_0_R1_SDA
J 0
(-3875 4910);
DISPLAY 0.489362 (-3875 4910);
FORCEPROP 2 LASTPROP $XRERR UNIQUE?
J 0
(-4115 4910);
DISPLAY 0.638298 (-4115 4910);
PAINT MONO (-4115 4910);
DISPLAY INVISIBLE (-4115 4910);
WIRE 16 -1 (-5025 1350)(-3075 1350);
FORCEPROP 2 LAST SIG_NAME JTAG_SCM_PLD_TCK
J 0
(-4925 1360);
DISPLAY 0.489362 (-4925 1360);
WIRE 16 -1 (-5025 1250)(-3075 1250);
FORCEPROP 2 LAST SIG_NAME CPLD_JTAG_EN
J 0
(-4925 1260);
DISPLAY 0.489362 (-4925 1260);
WIRE 16 -1 (-5025 1200)(-3075 1200);
FORCEPROP 2 LAST SIG_NAME CPLD_PROGRAMN
J 0
(-4925 1210);
DISPLAY 0.489362 (-4925 1210);
WIRE 16 -1 (-7150 4450)(-8025 4450);
FORCEPROP 2 LAST SIG_NAME SGPIO_SCM_INTR_N
J 0
(-7875 4460);
DISPLAY 0.489362 (-7875 4460);
WIRE 16 -1 (-6075 3700)(-6950 3700);
FORCEPROP 2 LAST SIG_NAME FM_P3V3_M2_2_EN
J 0
(-6850 3710);
DISPLAY 0.489362 (-6850 3710);
FORCEPROP 2 LASTPROP $XRERR UNIQUE?
J 0
(-7090 3710);
DISPLAY 0.638298 (-7090 3710);
PAINT MONO (-7090 3710);
DISPLAY INVISIBLE (-7090 3710);
WIRE 16 -1 (-6950 3650)(-6075 3650);
FORCEPROP 0 LAST CDS_PHYS_NET_NAME FM_SLOT2_PWRBRK0_R_N
J 0
(-6675 3700);
PAINT MONO (-6675 3700);
DISPLAY INVISIBLE (-6675 3700);
FORCEPROP 2 LAST SIG_NAME FM_SLOT2_PWRBRK0_R_N
J 0
(-6850 3660);
DISPLAY 0.489362 (-6850 3660);
FORCEPROP 2 LASTPROP $XRERR UNIQUE?
J 0
(-7090 3660);
DISPLAY 0.638298 (-7090 3660);
PAINT MONO (-7090 3660);
DISPLAY INVISIBLE (-7090 3660);
WIRE 16 -1 (-6950 3600)(-6075 3600);
FORCEPROP 0 LAST CDS_PHYS_NET_NAME FM_SLOT2_PWRBRK1_R_N
J 0
(-6675 3650);
PAINT MONO (-6675 3650);
DISPLAY INVISIBLE (-6675 3650);
FORCEPROP 2 LAST SIG_NAME FM_SLOT2_PWRBRK1_R_N
J 0
(-6850 3610);
DISPLAY 0.489362 (-6850 3610);
FORCEPROP 2 LASTPROP $XRERR UNIQUE?
J 0
(-7090 3610);
DISPLAY 0.638298 (-7090 3610);
PAINT MONO (-7090 3610);
DISPLAY INVISIBLE (-7090 3610);
WIRE 16 -1 (-7150 4550)(-8025 4550);
FORCEPROP 0 LAST $PNN SGPIO_SCM_DI_<0>
J 0
(-7875 4583);
DISPLAY INVISIBLE (-7875 4583);
FORCEPROP 2 LAST SIG_NAME SGPIO_SCM_DI_<0>
J 0
(-7875 4560);
DISPLAY 0.489362 (-7875 4560);
WIRE 16 -1 (-6950 4300)(-6075 4300);
FORCEPROP 2 LAST SIG_NAME FM_I3C_CPU1_MUX1_R_SEL
J 0
(-6850 4310);
DISPLAY 0.489362 (-6850 4310);
FORCEPROP 2 LASTPROP $XRERR UNIQUE?
J 0
(-7090 4310);
DISPLAY 0.638298 (-7090 4310);
PAINT MONO (-7090 4310);
DISPLAY INVISIBLE (-7090 4310);
WIRE 16 -1 (-6950 4550)(-6075 4550);
FORCEPROP 0 LAST $PNN SGPIO_SCM_DI_R<0>
J 0
(-6850 4583);
DISPLAY INVISIBLE (-6850 4583);
FORCEPROP 2 LAST SIG_NAME SGPIO_SCM_DI_R<0>
J 0
(-6850 4560);
DISPLAY 0.489362 (-6850 4560);
FORCEPROP 2 LASTPROP $XRERR UNIQUE?
J 0
(-7090 4560);
DISPLAY 0.638298 (-7090 4560);
PAINT MONO (-7090 4560);
DISPLAY INVISIBLE (-7090 4560);
WIRE 16 -1 (-6950 3250)(-6075 3250);
FORCEPROP 0 LAST CDS_PHYS_NET_NAME FM_SLOT1_PWRBRK0_R_N
J 0
(-6675 3300);
PAINT MONO (-6675 3300);
DISPLAY INVISIBLE (-6675 3300);
FORCEPROP 2 LAST SIG_NAME FM_SLOT1_PWRBRK0_R_N
J 0
(-6850 3260);
DISPLAY 0.489362 (-6850 3260);
FORCEPROP 2 LASTPROP $XRERR UNIQUE?
J 0
(-7090 3260);
DISPLAY 0.638298 (-7090 3260);
PAINT MONO (-7090 3260);
DISPLAY INVISIBLE (-7090 3260);
WIRE 16 -1 (-6075 3050)(-8025 3050);
FORCEPROP 0 LAST SIG_NAME OC_ALERT_N
J 0
(-7925 3060);
DISPLAY 0.489362 (-7925 3060);
WIRE 16 -1 (-6950 2700)(-6075 2700);
FORCEPROP 2 LAST SIG_NAME JTAG_SCM_TRST_R_N
J 0
(-6850 2710);
DISPLAY 0.489362 (-6850 2710);
FORCEPROP 2 LASTPROP $XRERR UNIQUE?
J 0
(-7090 2710);
DISPLAY 0.638298 (-7090 2710);
PAINT MONO (-7090 2710);
DISPLAY INVISIBLE (-7090 2710);
WIRE 16 -1 (-6950 3400)(-6075 3400);
FORCEPROP 2 LAST SIG_NAME P3V3_OCP_EN
J 0
(-6850 3410);
DISPLAY 0.489362 (-6850 3410);
FORCEPROP 2 LASTPROP $XRERR UNIQUE?
J 0
(-7090 3410);
DISPLAY 0.638298 (-7090 3410);
PAINT MONO (-7090 3410);
DISPLAY INVISIBLE (-7090 3410);
WIRE 16 -1 (-6075 3300)(-6950 3300);
FORCEPROP 2 LAST SIG_NAME P12V_OCP_EN
J 0
(-6850 3310);
DISPLAY 0.489362 (-6850 3310);
FORCEPROP 2 LASTPROP $XRERR UNIQUE?
J 0
(-7090 3310);
DISPLAY 0.638298 (-7090 3310);
PAINT MONO (-7090 3310);
DISPLAY INVISIBLE (-7090 3310);
WIRE 16 -1 (-3975 4250)(-3075 4250);
FORCEPROP 2 LAST SIG_NAME FM_CLK_100M_SLOT2_2_OE_R_N
J 0
(-3875 4260);
DISPLAY 0.489362 (-3875 4260);
FORCEPROP 2 LASTPROP $XRERR UNIQUE?
J 0
(-4115 4260);
DISPLAY 0.638298 (-4115 4260);
PAINT MONO (-4115 4260);
DISPLAY INVISIBLE (-4115 4260);
WIRE 16 -1 (-3975 5050)(-2025 5050);
FORCEPROP 2 LAST SIG_NAME RM_THROTTLE_N
J 0
(-2750 5060);
DISPLAY 0.489362 (-2750 5060);
WIRE 16 -1 (-3975 4350)(-2025 4350);
FORCEPROP 0 LAST SIG_NAME FPGA_DR_FAN_PWM
J 0
(-2750 4360);
DISPLAY 0.489362 (-2750 4360);
WIRE 16 -1 (-3975 4300)(-2025 4300);
FORCEPROP 0 LAST SIG_NAME FPGA_SR_FAN_PWM
J 0
(-2750 4310);
DISPLAY 0.489362 (-2750 4310);
WIRE 16 -1 (-2875 4950)(-2025 4950);
FORCEPROP 2 LAST SIG_NAME SMB_SCM_0_R_SCL
J 0
(-2750 4960);
DISPLAY 0.489362 (-2750 4960);
WIRE 16 -1 (-2875 4900)(-2025 4900);
FORCEPROP 2 LAST SIG_NAME SMB_SCM_0_R_SDA
J 0
(-2750 4910);
DISPLAY 0.489362 (-2750 4910);
WIRE 16 -1 (-2025 4850)(-2875 4850);
FORCEPROP 0 LAST SIG_NAME FM_E1S_3_CLK_OE_R
J 0
(-2750 4860);
DISPLAY 0.489362 (-2750 4860);
WIRE 16 -1 (-2025 4800)(-2875 4800);
FORCEPROP 0 LAST SIG_NAME FM_E1S_4_CLK_OE_R
J 0
(-2750 4810);
DISPLAY 0.489362 (-2750 4810);
WIRE 16 -1 (-2875 4750)(-2025 4750);
FORCEPROP 2 LAST SIG_NAME FM_CLK_100M_SLOT1_2_OE_N
J 0
(-2750 4760);
DISPLAY 0.489362 (-2750 4760);
WIRE 16 -1 (-2875 4600)(-2025 4600);
FORCEPROP 2 LAST SIG_NAME SMB_SCM_1_R_SDA
J 0
(-2750 4610);
DISPLAY 0.489362 (-2750 4610);
WIRE 16 -1 (-2875 4650)(-2025 4650);
FORCEPROP 2 LAST SIG_NAME SMB_SCM_1_R_SCL
J 0
(-2750 4660);
DISPLAY 0.489362 (-2750 4660);
WIRE 16 -1 (-2875 4200)(-2025 4200);
FORCEPROP 2 LAST SIG_NAME FM_CLK_100M_SLOT2_3_OE_N
J 0
(-2750 4210);
DISPLAY 0.489362 (-2750 4210);
WIRE 16 -1 (-2875 4250)(-2025 4250);
FORCEPROP 2 LAST SIG_NAME FM_CLK_100M_SLOT2_2_OE_N
J 0
(-2750 4260);
DISPLAY 0.489362 (-2750 4260);
WIRE 16 -1 (-2875 4100)(-2025 4100);
FORCEPROP 2 LAST SIG_NAME SCM_SYS_PWROK_R
J 0
(-2750 4110);
DISPLAY 0.489362 (-2750 4110);
WIRE 16 -1 (-5025 1450)(-3075 1450);
FORCEPROP 2 LAST SIG_NAME JTAG_SCM_PLD_TDI
J 0
(-4925 1460);
DISPLAY 0.489362 (-4925 1460);
WIRE 16 -1 (-5025 1400)(-3075 1400);
FORCEPROP 2 LAST SIG_NAME JTAG_SCM_PLD_TDO
J 0
(-4925 1410);
DISPLAY 0.489362 (-4925 1410);
WIRE 16 -1 (-5025 1300)(-3075 1300);
FORCEPROP 2 LAST SIG_NAME JTAG_SCM_PLD_TMS
J 0
(-4925 1310);
DISPLAY 0.489362 (-4925 1310);
WIRE 16 -1 (-6950 2750)(-6075 2750);
FORCEPROP 0 LAST CDS_PHYS_NET_NAME FM_SYS_THROTTLE_R_N
J 0
(-6925 2792);
PAINT MONO (-6925 2792);
DISPLAY INVISIBLE (-6925 2792);
FORCEPROP 0 LAST SIG_NAME FM_SYS_THROTTLE_R_N
J 0
(-6850 2760);
DISPLAY 0.489362 (-6850 2760);
FORCEPROP 2 LASTPROP $XRERR UNIQUE?
J 0
(-7090 2760);
DISPLAY 0.638298 (-7090 2760);
PAINT MONO (-7090 2760);
DISPLAY INVISIBLE (-7090 2760);
WIRE 16 -1 (-8025 3000)(-7150 3000);
FORCEPROP 2 LAST SIG_NAME SMB_CPU0_4_XLTR_SCL
J 0
(-7875 3010);
DISPLAY 0.489362 (-7875 3010);
WIRE 16 -1 (-8025 2950)(-7150 2950);
FORCEPROP 2 LAST SIG_NAME SMB_CPU0_4_XLTR_SDA
J 0
(-7875 2960);
DISPLAY 0.489362 (-7875 2960);
WIRE 16 -1 (-8025 2750)(-7150 2750);
FORCEPROP 0 LAST CDS_PHYS_NET_NAME FM_SYS_THROTTLE_N
J 0
(-8000 2792);
PAINT MONO (-8000 2792);
DISPLAY INVISIBLE (-8000 2792);
FORCEPROP 0 LAST SIG_NAME FM_SYS_THROTTLE_N
J 0
(-7850 2760);
DISPLAY 0.489362 (-7850 2760);
WIRE 16 -1 (-7150 2700)(-8025 2700);
FORCEPROP 0 LAST CDS_PHYS_NET_NAME JTAG_SCM_TRST_N
J 0
(-7750 2750);
PAINT MONO (-7750 2750);
DISPLAY INVISIBLE (-7750 2750);
FORCEPROP 2 LAST SIG_NAME JTAG_SCM_TRST_N
J 0
(-7850 2710);
DISPLAY 0.489362 (-7850 2710);
WIRE 16 -1 (-7150 3250)(-8025 3250);
FORCEPROP 2 LAST SIG_NAME FM_SLOT1_PWRBRK0_N
J 0
(-7875 3260);
DISPLAY 0.489362 (-7875 3260);
WIRE 16 -1 (-2875 3950)(-2025 3950);
FORCEPROP 2 LAST SIG_NAME FM_CLK_100M_SLOT1_3_OE_N
J 0
(-2750 3960);
DISPLAY 0.489362 (-2750 3960);
WIRE 16 -1 (-2025 3900)(-2875 3900);
FORCEPROP 0 LAST SIG_NAME FM_E1S_1_CLK_OE_R
J 0
(-2750 3910);
DISPLAY 0.489362 (-2750 3910);
WIRE 16 -1 (-2875 3800)(-2025 3800);
FORCEPROP 2 LAST SIG_NAME FM_CLK_100M_M2_2_OE_N
J 0
(-2750 3810);
DISPLAY 0.489362 (-2750 3810);
WIRE 16 -1 (-6075 2800)(-8025 2800);
FORCEPROP 0 LAST SIG_NAME FM_LED_ACTIVE_E1S_4
J 0
(-7875 2810);
DISPLAY 0.489362 (-7875 2810);
WIRE 16 -1 (-6075 2850)(-8025 2850);
FORCEPROP 0 LAST SIG_NAME FM_LED_ACTIVE_E1S_3
J 0
(-7875 2860);
DISPLAY 0.489362 (-7875 2860);
WIRE 16 -1 (-6075 2950)(-6950 2950);
FORCEPROP 2 LAST SIG_NAME SMB_CPU0_4_XLTR_R_SDA
J 0
(-6850 2960);
DISPLAY 0.489362 (-6850 2960);
FORCEPROP 2 LASTPROP $XRERR UNIQUE?
J 0
(-7090 2960);
DISPLAY 0.638298 (-7090 2960);
PAINT MONO (-7090 2960);
DISPLAY INVISIBLE (-7090 2960);
WIRE 16 -1 (-6075 3000)(-6950 3000);
FORCEPROP 2 LAST SIG_NAME SMB_CPU0_4_XLTR_R_SCL
J 0
(-6850 3010);
DISPLAY 0.489362 (-6850 3010);
FORCEPROP 2 LASTPROP $XRERR UNIQUE?
J 0
(-7090 3010);
DISPLAY 0.638298 (-7090 3010);
PAINT MONO (-7090 3010);
DISPLAY INVISIBLE (-7090 3010);
WIRE 16 -1 (-3975 4800)(-3075 4800);
FORCEPROP 0 LAST SIG_NAME FM_E1S_4_CLK_OE_N
J 0
(-3875 4810);
DISPLAY 0.489362 (-3875 4810);
FORCEPROP 2 LASTPROP $XRERR UNIQUE?
J 0
(-4115 4810);
DISPLAY 0.638298 (-4115 4810);
PAINT MONO (-4115 4810);
DISPLAY INVISIBLE (-4115 4810);
WIRE 16 -1 (-3975 4750)(-3075 4750);
FORCEPROP 2 LAST SIG_NAME FM_CLK_100M_SLOT1_2_OE_R_N
J 0
(-3875 4760);
DISPLAY 0.489362 (-3875 4760);
FORCEPROP 2 LASTPROP $XRERR UNIQUE?
J 0
(-4115 4760);
DISPLAY 0.638298 (-4115 4760);
PAINT MONO (-4115 4760);
DISPLAY INVISIBLE (-4115 4760);
WIRE 16 -1 (-2025 4700)(-3975 4700);
FORCEPROP 2 LAST SIG_NAME SCM_SPARE_1
J 0
(-3875 4710);
DISPLAY 0.489362 (-3875 4710);
WIRE 16 -1 (-3975 5000)(-2025 5000);
FORCEPROP 2 LAST SIG_NAME SCM_SYS_PWRBTN_N
J 0
(-3875 5010);
DISPLAY 0.489362 (-3875 5010);
WIRE 16 -1 (-3075 4950)(-3975 4950);
FORCEPROP 2 LAST SIG_NAME SMB_SCM_0_R1_SCL
J 0
(-3875 4960);
DISPLAY 0.489362 (-3875 4960);
FORCEPROP 2 LASTPROP $XRERR UNIQUE?
J 0
(-4115 4960);
DISPLAY 0.638298 (-4115 4960);
PAINT MONO (-4115 4960);
DISPLAY INVISIBLE (-4115 4960);
WIRE 16 -1 (-3975 4850)(-3075 4850);
FORCEPROP 0 LAST SIG_NAME FM_E1S_3_CLK_OE_N
J 0
(-3875 4860);
DISPLAY 0.489362 (-3875 4860);
FORCEPROP 2 LASTPROP $XRERR UNIQUE?
J 0
(-4115 4860);
DISPLAY 0.638298 (-4115 4860);
PAINT MONO (-4115 4860);
DISPLAY INVISIBLE (-4115 4860);
WIRE 16 -1 (-3075 4600)(-3975 4600);
FORCEPROP 2 LAST SIG_NAME SMB_SCM_1_R1_SDA
J 0
(-3875 4610);
DISPLAY 0.489362 (-3875 4610);
FORCEPROP 2 LASTPROP $XRERR UNIQUE?
J 0
(-4115 4610);
DISPLAY 0.638298 (-4115 4610);
PAINT MONO (-4115 4610);
DISPLAY INVISIBLE (-4115 4610);
WIRE 16 -1 (-2025 4550)(-3975 4550);
FORCEPROP 2 LAST SIG_NAME SCM_ROT_CPU_RST_R_N
J 0
(-2750 4560);
DISPLAY 0.489362 (-2750 4560);
WIRE 16 -1 (-2025 4500)(-3975 4500);
FORCEPROP 2 LAST SIG_NAME HPM_STBY_RST_N
J 0
(-2750 4510);
DISPLAY 0.489362 (-2750 4510);
WIRE 16 -1 (-3975 4450)(-2025 4450);
FORCEPROP 2 LAST SIG_NAME SMB_PSU1_ALERT
J 0
(-2750 4460);
DISPLAY 0.489362 (-2750 4460);
WIRE 16 -1 (-3975 4400)(-2025 4400);
FORCEPROP 2 LAST SIG_NAME SMB_PSU2_ALERT
J 0
(-2750 4410);
DISPLAY 0.489362 (-2750 4410);
WIRE 16 -1 (-8025 4850)(-7150 4850);
FORCEPROP 2 LAST SIG_NAME FM_I3C_CPU0_MUX1_SEL
J 0
(-7875 4860);
DISPLAY 0.489362 (-7875 4860);
WIRE 16 -1 (-8025 4900)(-7150 4900);
FORCEPROP 2 LAST SIG_NAME FM_I3C_CPU1_MUX1_OE_N
J 0
(-7875 4910);
DISPLAY 0.489362 (-7875 4910);
WIRE 16 -1 (-6950 4850)(-6075 4850);
FORCEPROP 2 LAST SIG_NAME FM_I3C_CPU0_MUX1_R_SEL
J 0
(-6850 4860);
DISPLAY 0.489362 (-6850 4860);
FORCEPROP 2 LASTPROP $XRERR UNIQUE?
J 0
(-7090 4860);
DISPLAY 0.638298 (-7090 4860);
PAINT MONO (-7090 4860);
DISPLAY INVISIBLE (-7090 4860);
WIRE 16 -1 (-8025 4800)(-7150 4800);
FORCEPROP 2 LAST SIG_NAME FM_I3C_CPU1_MUX0_OE_N
J 0
(-7875 4810);
DISPLAY 0.489362 (-7875 4810);
WIRE 16 -1 (-8025 4750)(-7150 4750);
FORCEPROP 2 LAST SIG_NAME SCM_JTAG_MUX_S1
J 0
(-7875 4760);
DISPLAY 0.489362 (-7875 4760);
WIRE 16 -1 (-7150 4650)(-8025 4650);
FORCEPROP 2 LAST SIG_NAME FM_I3C_CPU0_MUX1_OE_N
J 0
(-7875 4660);
DISPLAY 0.489362 (-7875 4660);
WIRE 16 -1 (-8025 4600)(-7150 4600);
FORCEPROP 2 LAST SIG_NAME SCM_JTAG_MUX_S0
J 0
(-7875 4610);
DISPLAY 0.489362 (-7875 4610);
WIRE 16 -1 (-8025 4700)(-7150 4700);
FORCEPROP 2 LAST SIG_NAME FM_I3C_CPU0_MUX0_SEL
J 0
(-7875 4710);
DISPLAY 0.489362 (-7875 4710);
FORCENOTE
BANK0 P3V3_STBY
(-5950 5800) 0;
DISPLAY LEFT (-5950 5800);
DISPLAY 3.148936 (-5950 5800);
QUIT
